G04 ================== begin FILE IDENTIFICATION RECORD ==================*
G04 Layout Name:  15105-sa.brd*
G04 Film Name:    BMASK*
G04 File Format:  Gerber RS274X*
G04 File Origin:  Cadence Allegro 16.5-S056*
G04 Origin Date:  Wed Nov 16 02:01:41 2016*
G04 *
G04 Layer:  VIA CLASS/SOLDERMASK_BOTTOM*
G04 Layer:  PIN/SOLDERMASK_BOTTOM*
G04 Layer:  PACKAGE GEOMETRY/SOLDERMASK_BOTTOM*
G04 Layer:  DRAWING FORMAT/LAYER_PCB_STORY*
G04 Layer:  DRAWING FORMAT/LAYER_SOLDER_B*
G04 Layer:  BOARD GEOMETRY/SOLDERMASK_BOTTOM*
G04 *
G04 Offset:    (0.00 0.00)*
G04 Mirror:    No*
G04 Mode:      Positive*
G04 Rotation:  0*
G04 FullContactRelief:  No*
G04 UndefLineWidth:     6.00*
G04 ================== end FILE IDENTIFICATION RECORD ====================*
%FSLAX35Y35*MOIN*%
%IR0*IPPOS*OFA0.00000B0.00000*MIA0B0*SFA1.00000B1.00000*%
%AMMACRO37*
4,1,40,.011,.007,
.011,-.007,
.010939,-.007695,
.010759,-.008368,
.010464,-.009,
.010064,-.009571,
.009571,-.010064,
.009,-.010464,
.008368,-.010759,
.007695,-.010939,
.007,-.011,
-.007,-.011,
-.007695,-.010939,
-.008368,-.010759,
-.009,-.010464,
-.009571,-.010064,
-.010064,-.009571,
-.010464,-.009,
-.010759,-.008368,
-.010939,-.007695,
-.011,-.007,
-.011,.007,
-.010939,.007695,
-.010759,.008368,
-.010464,.009,
-.010064,.009571,
-.009571,.010064,
-.009,.010464,
-.008368,.010759,
-.007695,.010939,
-.007,.011,
.007,.011,
.007695,.010939,
.008368,.010759,
.009,.010464,
.009571,.010064,
.010064,.009571,
.010464,.009,
.010759,.008368,
.010939,.007695,
.011,.007,
0.0*
%
%ADD37MACRO37*%
%AMMACRO49*
4,1,40,.013,-.017,
-.013,-.017,
-.013695,-.016939,
-.014368,-.016759,
-.015,-.016464,
-.015571,-.016064,
-.016064,-.015571,
-.016464,-.015,
-.016759,-.014368,
-.016939,-.013695,
-.017,-.013,
-.017,.013,
-.016939,.013695,
-.016759,.014368,
-.016464,.015,
-.016064,.015571,
-.015571,.016064,
-.015,.016464,
-.014368,.016759,
-.013695,.016939,
-.013,.017,
.013,.017,
.013695,.016939,
.014368,.016759,
.015,.016464,
.015571,.016064,
.016064,.015571,
.016464,.015,
.016759,.014368,
.016939,.013695,
.017,.013,
.017,-.013,
.016939,-.013695,
.016759,-.014368,
.016464,-.015,
.016064,-.015571,
.015571,-.016064,
.015,-.016464,
.014368,-.016759,
.013695,-.016939,
.013,-.017,
0.0*
%
%ADD49MACRO49*%
%AMMACRO25*
4,1,40,-.017,-.013,
-.017,.013,
-.016939,.013695,
-.016759,.014368,
-.016464,.015,
-.016064,.015571,
-.015571,.016064,
-.015,.016464,
-.014368,.016759,
-.013695,.016939,
-.013,.017,
.013,.017,
.013695,.016939,
.014368,.016759,
.015,.016464,
.015571,.016064,
.016064,.015571,
.016464,.015,
.016759,.014368,
.016939,.013695,
.017,.013,
.017,-.013,
.016939,-.013695,
.016759,-.014368,
.016464,-.015,
.016064,-.015571,
.015571,-.016064,
.015,-.016464,
.014368,-.016759,
.013695,-.016939,
.013,-.017,
-.013,-.017,
-.013695,-.016939,
-.014368,-.016759,
-.015,-.016464,
-.015571,-.016064,
-.016064,-.015571,
-.016464,-.015,
-.016759,-.014368,
-.016939,-.013695,
-.017,-.013,
0.0*
%
%ADD25MACRO25*%
%ADD40C,.02*%
%ADD57C,.04*%
%ADD62C,.05*%
%ADD29C,.032*%
%AMMACRO61*
4,1,40,-.007,-.004,
-.007,.004,
-.00697,.004347,
-.006879,.004684,
-.006732,.005,
-.006532,.005286,
-.006286,.005532,
-.006,.005732,
-.005684,.005879,
-.005347,.00597,
-.005,.006,
.005,.006,
.005347,.00597,
.005684,.005879,
.006,.005732,
.006286,.005532,
.006532,.005286,
.006732,.005,
.006879,.004684,
.00697,.004347,
.007,.004,
.007,-.004,
.00697,-.004347,
.006879,-.004684,
.006732,-.005,
.006532,-.005286,
.006286,-.005532,
.006,-.005732,
.005684,-.005879,
.005347,-.00597,
.005,-.006,
-.005,-.006,
-.005347,-.00597,
-.005684,-.005879,
-.006,-.005732,
-.006286,-.005532,
-.006532,-.005286,
-.006732,-.005,
-.006879,-.004684,
-.00697,-.004347,
-.007,-.004,
0.0*
%
%ADD61MACRO61*%
%AMMACRO63*
4,1,40,-.004,.007,
.004,.007,
.004347,.00697,
.004684,.006879,
.005,.006732,
.005286,.006532,
.005532,.006286,
.005732,.006,
.005879,.005684,
.00597,.005347,
.006,.005,
.006,-.005,
.00597,-.005347,
.005879,-.005684,
.005732,-.006,
.005532,-.006286,
.005286,-.006532,
.005,-.006732,
.004684,-.006879,
.004347,-.00697,
.004,-.007,
-.004,-.007,
-.004347,-.00697,
-.004684,-.006879,
-.005,-.006732,
-.005286,-.006532,
-.005532,-.006286,
-.005732,-.006,
-.005879,-.005684,
-.00597,-.005347,
-.006,-.005,
-.006,.005,
-.00597,.005347,
-.005879,.005684,
-.005732,.006,
-.005532,.006286,
-.005286,.006532,
-.005,.006732,
-.004684,.006879,
-.004347,.00697,
-.004,.007,
0.0*
%
%ADD63MACRO63*%
%ADD18C,.052*%
%ADD16C,.08*%
%ADD54C,.036*%
%ADD35C,.054*%
%ADD14C,.028*%
%ADD65C,.038*%
%ADD56C,.029*%
%AMMACRO55*
4,1,42,.01182,.09815,
.028621,.094612,
.044553,.08821,
.059131,.079139,
.071913,.067674,
.082509,.054164,
.090599,.039019,
.095935,.022699,
.098357,.005701,
.09779,-.01146,
.094252,-.028261,
.08785,-.044193,
.078779,-.058771,
.067314,-.071553,
.053804,-.082149,
.038659,-.090239,
.022339,-.095575,
.005341,-.097997,
-.01182,-.09743,
-.028621,-.093892,
-.044553,-.08749,
-.059131,-.078419,
-.071913,-.066954,
-.082509,-.053444,
-.090599,-.038299,
-.095935,-.021979,
-.098357,-.004981,
-.09779,.01218,
-.094252,.028981,
-.08785,.044913,
-.078779,.059491,
-.067314,.072273,
-.053804,.082869,
-.038659,.090959,
-.022339,.096295,
-.01182,.09815,
-.008112,.096406,
-.004157,.095333,
-.000076,.094962,
.004007,.095306,
.007968,.096354,
.011688,.098074,
.01182,.09815,
0.0*
%
%ADD55MACRO55*%
%ADD44C,.056*%
%ADD11C,.066*%
%ADD53C,.058*%
%ADD10C,.086*%
%ADD12C,.078*%
%AMMACRO58*
4,1,40,.0225,.007,
.022378,.008389,
.022018,.009736,
.021428,.011,
.020628,.012142,
.019642,.013128,
.0185,.013928,
.017236,.014518,
.015889,.014878,
.0145,.015,
-.0145,.015,
-.015889,.014878,
-.017236,.014518,
-.0185,.013928,
-.019642,.013128,
-.020628,.012142,
-.021428,.011,
-.022018,.009736,
-.022378,.008389,
-.0225,.007,
-.0225,-.007,
-.022378,-.008389,
-.022018,-.009736,
-.021428,-.011,
-.020628,-.012142,
-.019642,-.013128,
-.0185,-.013928,
-.017236,-.014518,
-.015889,-.014878,
-.0145,-.015,
.0145,-.015,
.015889,-.014878,
.017236,-.014518,
.0185,-.013928,
.019642,-.013128,
.020628,-.012142,
.021428,-.011,
.022018,-.009736,
.022378,-.008389,
.0225,-.007,
.0225,.007,
0.0*
%
%ADD58MACRO58*%
%AMMACRO30*
4,1,40,.007,-.011,
-.007,-.011,
-.007695,-.010939,
-.008368,-.010759,
-.009,-.010464,
-.009571,-.010064,
-.010064,-.009571,
-.010464,-.009,
-.010759,-.008368,
-.010939,-.007695,
-.011,-.007,
-.011,.007,
-.010939,.007695,
-.010759,.008368,
-.010464,.009,
-.010064,.009571,
-.009571,.010064,
-.009,.010464,
-.008368,.010759,
-.007695,.010939,
-.007,.011,
.007,.011,
.007695,.010939,
.008368,.010759,
.009,.010464,
.009571,.010064,
.010064,.009571,
.010464,.009,
.010759,.008368,
.010939,.007695,
.011,.007,
.011,-.007,
.010939,-.007695,
.010759,-.008368,
.010464,-.009,
.010064,-.009571,
.009571,-.010064,
.009,-.010464,
.008368,-.010759,
.007695,-.010939,
.007,-.011,
0.0*
%
%ADD30MACRO30*%
%AMMACRO23*
4,1,40,-.011,-.007,
-.011,.007,
-.010939,.007695,
-.010759,.008368,
-.010464,.009,
-.010064,.009571,
-.009571,.010064,
-.009,.010464,
-.008368,.010759,
-.007695,.010939,
-.007,.011,
.007,.011,
.007695,.010939,
.008368,.010759,
.009,.010464,
.009571,.010064,
.010064,.009571,
.010464,.009,
.010759,.008368,
.010939,.007695,
.011,.007,
.011,-.007,
.010939,-.007695,
.010759,-.008368,
.010464,-.009,
.010064,-.009571,
.009571,-.010064,
.009,-.010464,
.008368,-.010759,
.007695,-.010939,
.007,-.011,
-.007,-.011,
-.007695,-.010939,
-.008368,-.010759,
-.009,-.010464,
-.009571,-.010064,
-.010064,-.009571,
-.010464,-.009,
-.010759,-.008368,
-.010939,-.007695,
-.011,-.007,
0.0*
%
%ADD23MACRO23*%
%AMMACRO20*
4,1,40,-.012,-.008,
-.012,.008,
-.011939,.008695,
-.011759,.009368,
-.011464,.01,
-.011064,.010571,
-.010571,.011064,
-.01,.011464,
-.009368,.011759,
-.008695,.011939,
-.008,.012,
.008,.012,
.008695,.011939,
.009368,.011759,
.01,.011464,
.010571,.011064,
.011064,.010571,
.011464,.01,
.011759,.009368,
.011939,.008695,
.012,.008,
.012,-.008,
.011939,-.008695,
.011759,-.009368,
.011464,-.01,
.011064,-.010571,
.010571,-.011064,
.01,-.011464,
.009368,-.011759,
.008695,-.011939,
.008,-.012,
-.008,-.012,
-.008695,-.011939,
-.009368,-.011759,
-.01,-.011464,
-.010571,-.011064,
-.011064,-.010571,
-.011464,-.01,
-.011759,-.009368,
-.011939,-.008695,
-.012,-.008,
0.0*
%
%ADD20MACRO20*%
%AMMACRO33*
4,1,40,-.008,.012,
.008,.012,
.008695,.011939,
.009368,.011759,
.01,.011464,
.010571,.011064,
.011064,.010571,
.011464,.01,
.011759,.009368,
.011939,.008695,
.012,.008,
.012,-.008,
.011939,-.008695,
.011759,-.009368,
.011464,-.01,
.011064,-.010571,
.010571,-.011064,
.01,-.011464,
.009368,-.011759,
.008695,-.011939,
.008,-.012,
-.008,-.012,
-.008695,-.011939,
-.009368,-.011759,
-.01,-.011464,
-.010571,-.011064,
-.011064,-.010571,
-.011464,-.01,
-.011759,-.009368,
-.011939,-.008695,
-.012,-.008,
-.012,.008,
-.011939,.008695,
-.011759,.009368,
-.011464,.01,
-.011064,.010571,
-.010571,.011064,
-.01,.011464,
-.009368,.011759,
-.008695,.011939,
-.008,.012,
0.0*
%
%ADD33MACRO33*%
%AMMACRO48*
4,1,40,-.013,.017,
.013,.017,
.013695,.016939,
.014368,.016759,
.015,.016464,
.015571,.016064,
.016064,.015571,
.016464,.015,
.016759,.014368,
.016939,.013695,
.017,.013,
.017,-.013,
.016939,-.013695,
.016759,-.014368,
.016464,-.015,
.016064,-.015571,
.015571,-.016064,
.015,-.016464,
.014368,-.016759,
.013695,-.016939,
.013,-.017,
-.013,-.017,
-.013695,-.016939,
-.014368,-.016759,
-.015,-.016464,
-.015571,-.016064,
-.016064,-.015571,
-.016464,-.015,
-.016759,-.014368,
-.016939,-.013695,
-.017,-.013,
-.017,.013,
-.016939,.013695,
-.016759,.014368,
-.016464,.015,
-.016064,.015571,
-.015571,.016064,
-.015,.016464,
-.014368,.016759,
-.013695,.016939,
-.013,.017,
0.0*
%
%ADD48MACRO48*%
%AMMACRO67*
4,1,40,.017,.013,
.017,-.013,
.016939,-.013695,
.016759,-.014368,
.016464,-.015,
.016064,-.015571,
.015571,-.016064,
.015,-.016464,
.014368,-.016759,
.013695,-.016939,
.013,-.017,
-.013,-.017,
-.013695,-.016939,
-.014368,-.016759,
-.015,-.016464,
-.015571,-.016064,
-.016064,-.015571,
-.016464,-.015,
-.016759,-.014368,
-.016939,-.013695,
-.017,-.013,
-.017,.013,
-.016939,.013695,
-.016759,.014368,
-.016464,.015,
-.016064,.015571,
-.015571,.016064,
-.015,.016464,
-.014368,.016759,
-.013695,.016939,
-.013,.017,
.013,.017,
.013695,.016939,
.014368,.016759,
.015,.016464,
.015571,.016064,
.016064,.015571,
.016464,.015,
.016759,.014368,
.016939,.013695,
.017,.013,
0.0*
%
%ADD67MACRO67*%
%AMMACRO31*
4,1,40,.007,-.011,
-.007,-.011,
-.007695,-.010939,
-.008368,-.010759,
-.009,-.010464,
-.009571,-.010064,
-.010064,-.009571,
-.010464,-.009,
-.010759,-.008368,
-.010939,-.007695,
-.011,-.007,
-.011,.007,
-.010939,.007695,
-.010759,.008368,
-.010464,.009,
-.010064,.009571,
-.009571,.010064,
-.009,.010464,
-.008368,.010759,
-.007695,.010939,
-.007,.011,
.007,.011,
.007695,.010939,
.008368,.010759,
.009,.010464,
.009571,.010064,
.010064,.009571,
.010464,.009,
.010759,.008368,
.010939,.007695,
.011,.007,
.011,-.007,
.010939,-.007695,
.010759,-.008368,
.010464,-.009,
.010064,-.009571,
.009571,-.010064,
.009,-.010464,
.008368,-.010759,
.007695,-.010939,
.007,-.011,
0.0*
%
%ADD31MACRO31*%
%AMMACRO24*
4,1,40,-.011,-.007,
-.011,.007,
-.010939,.007695,
-.010759,.008368,
-.010464,.009,
-.010064,.009571,
-.009571,.010064,
-.009,.010464,
-.008368,.010759,
-.007695,.010939,
-.007,.011,
.007,.011,
.007695,.010939,
.008368,.010759,
.009,.010464,
.009571,.010064,
.010064,.009571,
.010464,.009,
.010759,.008368,
.010939,.007695,
.011,.007,
.011,-.007,
.010939,-.007695,
.010759,-.008368,
.010464,-.009,
.010064,-.009571,
.009571,-.010064,
.009,-.010464,
.008368,-.010759,
.007695,-.010939,
.007,-.011,
-.007,-.011,
-.007695,-.010939,
-.008368,-.010759,
-.009,-.010464,
-.009571,-.010064,
-.010064,-.009571,
-.010464,-.009,
-.010759,-.008368,
-.010939,-.007695,
-.011,-.007,
0.0*
%
%ADD24MACRO24*%
%AMMACRO21*
4,1,40,-.012,-.008,
-.012,.008,
-.011939,.008695,
-.011759,.009368,
-.011464,.01,
-.011064,.010571,
-.010571,.011064,
-.01,.011464,
-.009368,.011759,
-.008695,.011939,
-.008,.012,
.008,.012,
.008695,.011939,
.009368,.011759,
.01,.011464,
.010571,.011064,
.011064,.010571,
.011464,.01,
.011759,.009368,
.011939,.008695,
.012,.008,
.012,-.008,
.011939,-.008695,
.011759,-.009368,
.011464,-.01,
.011064,-.010571,
.010571,-.011064,
.01,-.011464,
.009368,-.011759,
.008695,-.011939,
.008,-.012,
-.008,-.012,
-.008695,-.011939,
-.009368,-.011759,
-.01,-.011464,
-.010571,-.011064,
-.011064,-.010571,
-.011464,-.01,
-.011759,-.009368,
-.011939,-.008695,
-.012,-.008,
0.0*
%
%ADD21MACRO21*%
%AMMACRO32*
4,1,40,-.008,.012,
.008,.012,
.008695,.011939,
.009368,.011759,
.01,.011464,
.010571,.011064,
.011064,.010571,
.011464,.01,
.011759,.009368,
.011939,.008695,
.012,.008,
.012,-.008,
.011939,-.008695,
.011759,-.009368,
.011464,-.01,
.011064,-.010571,
.010571,-.011064,
.01,-.011464,
.009368,-.011759,
.008695,-.011939,
.008,-.012,
-.008,-.012,
-.008695,-.011939,
-.009368,-.011759,
-.01,-.011464,
-.010571,-.011064,
-.011064,-.010571,
-.011464,-.01,
-.011759,-.009368,
-.011939,-.008695,
-.012,-.008,
-.012,.008,
-.011939,.008695,
-.011759,.009368,
-.011464,.01,
-.011064,.010571,
-.010571,.011064,
-.01,.011464,
-.009368,.011759,
-.008695,.011939,
-.008,.012,
0.0*
%
%ADD32MACRO32*%
%AMMACRO47*
4,1,40,-.013,.017,
.013,.017,
.013695,.016939,
.014368,.016759,
.015,.016464,
.015571,.016064,
.016064,.015571,
.016464,.015,
.016759,.014368,
.016939,.013695,
.017,.013,
.017,-.013,
.016939,-.013695,
.016759,-.014368,
.016464,-.015,
.016064,-.015571,
.015571,-.016064,
.015,-.016464,
.014368,-.016759,
.013695,-.016939,
.013,-.017,
-.013,-.017,
-.013695,-.016939,
-.014368,-.016759,
-.015,-.016464,
-.015571,-.016064,
-.016064,-.015571,
-.016464,-.015,
-.016759,-.014368,
-.016939,-.013695,
-.017,-.013,
-.017,.013,
-.016939,.013695,
-.016759,.014368,
-.016464,.015,
-.016064,.015571,
-.015571,.016064,
-.015,.016464,
-.014368,.016759,
-.013695,.016939,
-.013,.017,
0.0*
%
%ADD47MACRO47*%
%AMMACRO68*
4,1,40,.017,.013,
.017,-.013,
.016939,-.013695,
.016759,-.014368,
.016464,-.015,
.016064,-.015571,
.015571,-.016064,
.015,-.016464,
.014368,-.016759,
.013695,-.016939,
.013,-.017,
-.013,-.017,
-.013695,-.016939,
-.014368,-.016759,
-.015,-.016464,
-.015571,-.016064,
-.016064,-.015571,
-.016464,-.015,
-.016759,-.014368,
-.016939,-.013695,
-.017,-.013,
-.017,.013,
-.016939,.013695,
-.016759,.014368,
-.016464,.015,
-.016064,.015571,
-.015571,.016064,
-.015,.016464,
-.014368,.016759,
-.013695,.016939,
-.013,.017,
.013,.017,
.013695,.016939,
.014368,.016759,
.015,.016464,
.015571,.016064,
.016064,.015571,
.016464,.015,
.016759,.014368,
.016939,.013695,
.017,.013,
0.0*
%
%ADD68MACRO68*%
%ADD66R,.04X.014*%
%ADD45R,.04X.016*%
%ADD52O,.046X.041*%
%ADD46R,.016X.04*%
%AMMACRO64*
4,1,40,.004,-.007,
-.004,-.007,
-.004347,-.00697,
-.004684,-.006879,
-.005,-.006732,
-.005286,-.006532,
-.005532,-.006286,
-.005732,-.006,
-.005879,-.005684,
-.00597,-.005347,
-.006,-.005,
-.006,.005,
-.00597,.005347,
-.005879,.005684,
-.005732,.006,
-.005532,.006286,
-.005286,.006532,
-.005,.006732,
-.004684,.006879,
-.004347,.00697,
-.004,.007,
.004,.007,
.004347,.00697,
.004684,.006879,
.005,.006732,
.005286,.006532,
.005532,.006286,
.005732,.006,
.005879,.005684,
.00597,.005347,
.006,.005,
.006,-.005,
.00597,-.005347,
.005879,-.005684,
.005732,-.006,
.005532,-.006286,
.005286,-.006532,
.005,-.006732,
.004684,-.006879,
.004347,-.00697,
.004,-.007,
0.0*
%
%ADD64MACRO64*%
%AMMACRO60*
4,1,40,.007,.004,
.007,-.004,
.00697,-.004347,
.006879,-.004684,
.006732,-.005,
.006532,-.005286,
.006286,-.005532,
.006,-.005732,
.005684,-.005879,
.005347,-.00597,
.005,-.006,
-.005,-.006,
-.005347,-.00597,
-.005684,-.005879,
-.006,-.005732,
-.006286,-.005532,
-.006532,-.005286,
-.006732,-.005,
-.006879,-.004684,
-.00697,-.004347,
-.007,-.004,
-.007,.004,
-.00697,.004347,
-.006879,.004684,
-.006732,.005,
-.006532,.005286,
-.006286,.005532,
-.006,.005732,
-.005684,.005879,
-.005347,.00597,
-.005,.006,
.005,.006,
.005347,.00597,
.005684,.005879,
.006,.005732,
.006286,.005532,
.006532,.005286,
.006732,.005,
.006879,.004684,
.00697,.004347,
.007,.004,
0.0*
%
%ADD60MACRO60*%
%ADD41R,.022X.091*%
%ADD34C,.107*%
%ADD15C,.315*%
%ADD13R,.045X.055*%
%ADD51R,.016X.048*%
%ADD22R,.055X.045*%
%ADD17C,.128*%
%ADD19C,.256*%
%AMMACRO69*
4,1,40,-.007,.0225,
-.008389,.022378,
-.009736,.022018,
-.011,.021428,
-.012142,.020628,
-.013128,.019642,
-.013928,.0185,
-.014518,.017236,
-.014878,.015889,
-.015,.0145,
-.015,-.0145,
-.014878,-.015889,
-.014518,-.017236,
-.013928,-.0185,
-.013128,-.019642,
-.012142,-.020628,
-.011,-.021428,
-.009736,-.022018,
-.008389,-.022378,
-.007,-.0225,
.007,-.0225,
.008389,-.022378,
.009736,-.022018,
.011,-.021428,
.012142,-.020628,
.013128,-.019642,
.013928,-.0185,
.014518,-.017236,
.014878,-.015889,
.015,-.0145,
.015,.0145,
.014878,.015889,
.014518,.017236,
.013928,.0185,
.013128,.019642,
.012142,.020628,
.011,.021428,
.009736,.022018,
.008389,.022378,
.007,.0225,
-.007,.0225,
0.0*
%
%ADD69MACRO69*%
%AMMACRO59*
4,1,40,-.012,-.024,
.012,-.024,
.013389,-.023878,
.014736,-.023518,
.016,-.022928,
.017142,-.022128,
.018128,-.021142,
.018928,-.02,
.019518,-.018736,
.019878,-.017389,
.02,-.016,
.02,.016,
.019878,.017389,
.019518,.018736,
.018928,.02,
.018128,.021142,
.017142,.022128,
.016,.022928,
.014736,.023518,
.013389,.023878,
.012,.024,
-.012,.024,
-.013389,.023878,
-.014736,.023518,
-.016,.022928,
-.017142,.022128,
-.018128,.021142,
-.018928,.02,
-.019518,.018736,
-.019878,.017389,
-.02,.016,
-.02,-.016,
-.019878,-.017389,
-.019518,-.018736,
-.018928,-.02,
-.018128,-.021142,
-.017142,-.022128,
-.016,-.022928,
-.014736,-.023518,
-.013389,-.023878,
-.012,-.024,
0.0*
%
%ADD59MACRO59*%
%AMMACRO42*
4,1,40,.012,.008,
.012,-.008,
.011939,-.008695,
.011759,-.009368,
.011464,-.01,
.011064,-.010571,
.010571,-.011064,
.01,-.011464,
.009368,-.011759,
.008695,-.011939,
.008,-.012,
-.008,-.012,
-.008695,-.011939,
-.009368,-.011759,
-.01,-.011464,
-.010571,-.011064,
-.011064,-.010571,
-.011464,-.01,
-.011759,-.009368,
-.011939,-.008695,
-.012,-.008,
-.012,.008,
-.011939,.008695,
-.011759,.009368,
-.011464,.01,
-.011064,.010571,
-.010571,.011064,
-.01,.011464,
-.009368,.011759,
-.008695,.011939,
-.008,.012,
.008,.012,
.008695,.011939,
.009368,.011759,
.01,.011464,
.010571,.011064,
.011064,.010571,
.011464,.01,
.011759,.009368,
.011939,.008695,
.012,.008,
0.0*
%
%ADD42MACRO42*%
%AMMACRO38*
4,1,40,.008,-.012,
-.008,-.012,
-.008695,-.011939,
-.009368,-.011759,
-.01,-.011464,
-.010571,-.011064,
-.011064,-.010571,
-.011464,-.01,
-.011759,-.009368,
-.011939,-.008695,
-.012,-.008,
-.012,.008,
-.011939,.008695,
-.011759,.009368,
-.011464,.01,
-.011064,.010571,
-.010571,.011064,
-.01,.011464,
-.009368,.011759,
-.008695,.011939,
-.008,.012,
.008,.012,
.008695,.011939,
.009368,.011759,
.01,.011464,
.010571,.011064,
.011064,.010571,
.011464,.01,
.011759,.009368,
.011939,.008695,
.012,.008,
.012,-.008,
.011939,-.008695,
.011759,-.009368,
.011464,-.01,
.011064,-.010571,
.010571,-.011064,
.01,-.011464,
.009368,-.011759,
.008695,-.011939,
.008,-.012,
0.0*
%
%ADD38MACRO38*%
%AMMACRO27*
4,1,40,-.007,.011,
.007,.011,
.007695,.010939,
.008368,.010759,
.009,.010464,
.009571,.010064,
.010064,.009571,
.010464,.009,
.010759,.008368,
.010939,.007695,
.011,.007,
.011,-.007,
.010939,-.007695,
.010759,-.008368,
.010464,-.009,
.010064,-.009571,
.009571,-.010064,
.009,-.010464,
.008368,-.010759,
.007695,-.010939,
.007,-.011,
-.007,-.011,
-.007695,-.010939,
-.008368,-.010759,
-.009,-.010464,
-.009571,-.010064,
-.010064,-.009571,
-.010464,-.009,
-.010759,-.008368,
-.010939,-.007695,
-.011,-.007,
-.011,.007,
-.010939,.007695,
-.010759,.008368,
-.010464,.009,
-.010064,.009571,
-.009571,.010064,
-.009,.010464,
-.008368,.010759,
-.007695,.010939,
-.007,.011,
0.0*
%
%ADD27MACRO27*%
%AMMACRO36*
4,1,40,.011,.007,
.011,-.007,
.010939,-.007695,
.010759,-.008368,
.010464,-.009,
.010064,-.009571,
.009571,-.010064,
.009,-.010464,
.008368,-.010759,
.007695,-.010939,
.007,-.011,
-.007,-.011,
-.007695,-.010939,
-.008368,-.010759,
-.009,-.010464,
-.009571,-.010064,
-.010064,-.009571,
-.010464,-.009,
-.010759,-.008368,
-.010939,-.007695,
-.011,-.007,
-.011,.007,
-.010939,.007695,
-.010759,.008368,
-.010464,.009,
-.010064,.009571,
-.009571,.010064,
-.009,.010464,
-.008368,.010759,
-.007695,.010939,
-.007,.011,
.007,.011,
.007695,.010939,
.008368,.010759,
.009,.010464,
.009571,.010064,
.010064,.009571,
.010464,.009,
.010759,.008368,
.010939,.007695,
.011,.007,
0.0*
%
%ADD36MACRO36*%
%AMMACRO50*
4,1,40,.013,-.017,
-.013,-.017,
-.013695,-.016939,
-.014368,-.016759,
-.015,-.016464,
-.015571,-.016064,
-.016064,-.015571,
-.016464,-.015,
-.016759,-.014368,
-.016939,-.013695,
-.017,-.013,
-.017,.013,
-.016939,.013695,
-.016759,.014368,
-.016464,.015,
-.016064,.015571,
-.015571,.016064,
-.015,.016464,
-.014368,.016759,
-.013695,.016939,
-.013,.017,
.013,.017,
.013695,.016939,
.014368,.016759,
.015,.016464,
.015571,.016064,
.016064,.015571,
.016464,.015,
.016759,.014368,
.016939,.013695,
.017,.013,
.017,-.013,
.016939,-.013695,
.016759,-.014368,
.016464,-.015,
.016064,-.015571,
.015571,-.016064,
.015,-.016464,
.014368,-.016759,
.013695,-.016939,
.013,-.017,
0.0*
%
%ADD50MACRO50*%
%AMMACRO26*
4,1,40,-.017,-.013,
-.017,.013,
-.016939,.013695,
-.016759,.014368,
-.016464,.015,
-.016064,.015571,
-.015571,.016064,
-.015,.016464,
-.014368,.016759,
-.013695,.016939,
-.013,.017,
.013,.017,
.013695,.016939,
.014368,.016759,
.015,.016464,
.015571,.016064,
.016064,.015571,
.016464,.015,
.016759,.014368,
.016939,.013695,
.017,.013,
.017,-.013,
.016939,-.013695,
.016759,-.014368,
.016464,-.015,
.016064,-.015571,
.015571,-.016064,
.015,-.016464,
.014368,-.016759,
.013695,-.016939,
.013,-.017,
-.013,-.017,
-.013695,-.016939,
-.014368,-.016759,
-.015,-.016464,
-.015571,-.016064,
-.016064,-.015571,
-.016464,-.015,
-.016759,-.014368,
-.016939,-.013695,
-.017,-.013,
0.0*
%
%ADD26MACRO26*%
%AMMACRO43*
4,1,40,.012,.008,
.012,-.008,
.011939,-.008695,
.011759,-.009368,
.011464,-.01,
.011064,-.010571,
.010571,-.011064,
.01,-.011464,
.009368,-.011759,
.008695,-.011939,
.008,-.012,
-.008,-.012,
-.008695,-.011939,
-.009368,-.011759,
-.01,-.011464,
-.010571,-.011064,
-.011064,-.010571,
-.011464,-.01,
-.011759,-.009368,
-.011939,-.008695,
-.012,-.008,
-.012,.008,
-.011939,.008695,
-.011759,.009368,
-.011464,.01,
-.011064,.010571,
-.010571,.011064,
-.01,.011464,
-.009368,.011759,
-.008695,.011939,
-.008,.012,
.008,.012,
.008695,.011939,
.009368,.011759,
.01,.011464,
.010571,.011064,
.011064,.010571,
.011464,.01,
.011759,.009368,
.011939,.008695,
.012,.008,
0.0*
%
%ADD43MACRO43*%
%AMMACRO39*
4,1,40,.008,-.012,
-.008,-.012,
-.008695,-.011939,
-.009368,-.011759,
-.01,-.011464,
-.010571,-.011064,
-.011064,-.010571,
-.011464,-.01,
-.011759,-.009368,
-.011939,-.008695,
-.012,-.008,
-.012,.008,
-.011939,.008695,
-.011759,.009368,
-.011464,.01,
-.011064,.010571,
-.010571,.011064,
-.01,.011464,
-.009368,.011759,
-.008695,.011939,
-.008,.012,
.008,.012,
.008695,.011939,
.009368,.011759,
.01,.011464,
.010571,.011064,
.011064,.010571,
.011464,.01,
.011759,.009368,
.011939,.008695,
.012,.008,
.012,-.008,
.011939,-.008695,
.011759,-.009368,
.011464,-.01,
.011064,-.010571,
.010571,-.011064,
.01,-.011464,
.009368,-.011759,
.008695,-.011939,
.008,-.012,
0.0*
%
%ADD39MACRO39*%
%AMMACRO28*
4,1,40,-.007,.011,
.007,.011,
.007695,.010939,
.008368,.010759,
.009,.010464,
.009571,.010064,
.010064,.009571,
.010464,.009,
.010759,.008368,
.010939,.007695,
.011,.007,
.011,-.007,
.010939,-.007695,
.010759,-.008368,
.010464,-.009,
.010064,-.009571,
.009571,-.010064,
.009,-.010464,
.008368,-.010759,
.007695,-.010939,
.007,-.011,
-.007,-.011,
-.007695,-.010939,
-.008368,-.010759,
-.009,-.010464,
-.009571,-.010064,
-.010064,-.009571,
-.010464,-.009,
-.010759,-.008368,
-.010939,-.007695,
-.011,-.007,
-.011,.007,
-.010939,.007695,
-.010759,.008368,
-.010464,.009,
-.010064,.009571,
-.009571,.010064,
-.009,.010464,
-.008368,.010759,
-.007695,.010939,
-.007,.011,
0.0*
%
%ADD28MACRO28*%
%ADD70C,.006*%
G75*
%LPD*%
G75*
G36*
G01X443214Y897938D02*
Y883420D01*
X111905D01*
Y897938D01*
X443214D01*
G37*
G36*
G01X860537D02*
Y883420D01*
X529228D01*
Y897938D01*
X860537D01*
G37*
G36*
G01X965900Y16280D02*
Y3406D01*
X981648D01*
Y16280D01*
X965900D01*
G37*
G36*
G01X1356600Y897938D02*
Y883420D01*
X1025291D01*
Y897938D01*
X1356600D01*
G37*
G54D10*
X700Y19100D03*
X16200Y120100D03*
X27200Y821800D03*
X33800Y872600D03*
X1384200Y122800D03*
X1373200Y823500D03*
X1415100Y-36700D03*
X1389800Y879000D03*
G54D20*
X54970Y301816D03*
X54977Y298371D03*
X54800Y307100D03*
X54978Y294934D03*
X44800Y422000D03*
Y426000D03*
X65382Y295207D03*
X140800Y510500D03*
X140572Y505467D03*
X141816Y517120D03*
X142300Y522000D03*
X272800Y759000D03*
X555280Y137538D03*
X555300Y134094D03*
X626300Y354600D03*
X833600Y176200D03*
Y179700D03*
X875100Y52700D03*
X1039817Y14710D03*
X1327800Y250000D03*
G54D11*
X31977Y126614D03*
Y116614D03*
X91189Y126614D03*
Y116614D03*
Y136614D03*
G54D21*
X51370Y301816D03*
X51377Y298371D03*
X51200Y307100D03*
X61782Y295207D03*
X51378Y294934D03*
X41200Y422000D03*
Y426000D03*
X137200Y510500D03*
X136972Y505467D03*
X138216Y517120D03*
X138700Y522000D03*
X269200Y759000D03*
X551680Y137538D03*
X551700Y134094D03*
X622700Y354600D03*
X830000Y176200D03*
Y179700D03*
X871500Y52700D03*
X1036217Y14710D03*
X1324200Y250000D03*
G54D30*
X93300Y476400D03*
Y472400D03*
X80642Y463549D03*
X77500Y478600D03*
X93300Y484600D03*
Y480400D03*
X70800Y498500D03*
X70408Y506552D03*
X80800Y546500D03*
Y530500D03*
Y542500D03*
Y522500D03*
Y550500D03*
X80622Y562789D03*
X76700Y729300D03*
Y733300D03*
X114400Y288100D03*
X108400Y731900D03*
Y727900D03*
X139146Y430391D03*
X189500Y403300D03*
X189700Y419800D03*
X210802Y479619D03*
Y475619D03*
X206826Y448165D03*
X222838Y466300D03*
Y462300D03*
X211023Y487704D03*
Y483704D03*
X210050Y495744D03*
Y491744D03*
X209800Y525500D03*
Y521500D03*
Y534500D03*
Y530500D03*
X222800Y550500D03*
Y558500D03*
Y554500D03*
X239800Y478000D03*
X261838Y477600D03*
X249800Y494100D03*
X239800Y490000D03*
Y486000D03*
Y482000D03*
X261838Y481600D03*
X260300Y588500D03*
Y593000D03*
X294300Y578500D03*
Y583000D03*
Y588500D03*
X507000Y788700D03*
X712163Y37236D03*
X715370Y29700D03*
X715390Y25490D03*
X715130Y53200D03*
Y49100D03*
X862860Y788880D03*
X878510Y792910D03*
X952800Y67900D03*
Y72000D03*
X1017146Y57597D03*
X1043500Y36615D03*
G54D12*
X26977Y151614D03*
X96189D03*
G54D22*
X50800Y334700D03*
Y342300D03*
X85400Y268400D03*
Y260800D03*
X87561Y317727D03*
Y325327D03*
X228500Y142700D03*
Y150300D03*
X582363Y237408D03*
Y229808D03*
X669163Y243108D03*
Y250708D03*
X693163Y243108D03*
X677163D03*
X685163D03*
X704700Y278200D03*
X693163Y250708D03*
X677163D03*
X685163D03*
X704700Y285800D03*
X708600Y238700D03*
X716600D03*
X724600D03*
X732600D03*
X708600Y246300D03*
X716600D03*
X724600D03*
X732600D03*
X719900Y278200D03*
X712300D03*
X735100D03*
X727500D03*
X719900Y285800D03*
X712300D03*
X735100D03*
X727500D03*
X1242000Y221800D03*
Y214200D03*
X1234000Y221800D03*
Y214200D03*
X1236500Y266200D03*
Y273800D03*
X1228500Y266200D03*
Y273800D03*
X1244500Y266200D03*
Y273800D03*
X1250000Y221800D03*
Y214200D03*
X1258500Y221800D03*
Y214200D03*
X1252500Y266200D03*
Y273800D03*
X1260500Y266200D03*
Y273800D03*
X1363500Y260200D03*
Y267800D03*
G54D13*
X31300Y268800D03*
X38900D03*
X39700Y278500D03*
X32100D03*
X39800Y308300D03*
X32200D03*
X57100Y315100D03*
X64700D03*
X98020Y307120D03*
X89776Y291298D03*
X82176D03*
X105620Y307120D03*
X248700Y177000D03*
X256300D03*
X267700Y166000D03*
X248700Y185000D03*
X256300D03*
X275300Y166000D03*
X570063Y253608D03*
X592763Y256608D03*
X600363D03*
X577663Y253608D03*
X628863Y254608D03*
X621263D03*
X628600Y362100D03*
X621000D03*
X930300Y267000D03*
X922700D03*
X930300Y275000D03*
X922700D03*
X930300Y283000D03*
X922700D03*
X965200Y267500D03*
X972800D03*
X965200Y275500D03*
X972800D03*
X965200Y283500D03*
X972800D03*
X1311200Y250500D03*
X1346300Y240000D03*
X1338700D03*
X1346300Y248000D03*
X1338700D03*
X1318800Y250500D03*
G54D31*
X96700Y476400D03*
Y472400D03*
X84042Y463549D03*
X80900Y478600D03*
X96700Y484600D03*
Y480400D03*
X74200Y498500D03*
X73808Y506552D03*
X84200Y546500D03*
Y530500D03*
Y542500D03*
Y522500D03*
Y550500D03*
X84022Y562789D03*
X80100Y729300D03*
Y733300D03*
X117800Y288100D03*
X111800Y731900D03*
Y727900D03*
X142546Y430391D03*
X192900Y403300D03*
X193100Y419800D03*
X214202Y479619D03*
Y475619D03*
X210226Y448165D03*
X226238Y466300D03*
Y462300D03*
X214423Y487704D03*
Y483704D03*
X213450Y495744D03*
Y491744D03*
X213200Y525500D03*
Y521500D03*
Y534500D03*
Y530500D03*
X226200Y550500D03*
Y558500D03*
Y554500D03*
X243200Y478000D03*
X265238Y477600D03*
X253200Y494100D03*
X243200Y490000D03*
Y486000D03*
Y482000D03*
X265238Y481600D03*
X263700Y588500D03*
Y593000D03*
X297700Y578500D03*
Y583000D03*
Y588500D03*
X510400Y788700D03*
X715563Y37236D03*
X718770Y29700D03*
X718790Y25490D03*
X718530Y53200D03*
Y49100D03*
X866260Y788880D03*
X881910Y792910D03*
X956200Y67900D03*
Y72000D03*
X1020546Y57597D03*
X1046900Y36615D03*
G54D40*
G01X127746Y-260199D02*
X95746D01*
G01X127746Y-276199D02*
Y-356199D01*
G01D02*
X1310146D01*
G01X127746Y-311699D02*
X1310146D01*
G01X123746Y-260199D02*
G02I-12000J0D01*
G01X118596D02*
G02I-6850J0D01*
G01X111746Y-276199D02*
Y-244199D01*
G01X127746Y-276199D02*
X1310146D01*
G01X522646D02*
Y-356199D01*
G01X660146Y-276199D02*
Y-356199D01*
G01X775146Y-276199D02*
Y-356199D01*
G01X942646Y-276199D02*
Y-356199D01*
G01X1112646Y-276199D02*
Y-356199D01*
G01X1310146Y-276199D02*
Y-356199D01*
G01X1342146Y-260199D02*
X1310146D01*
G01X1338146D02*
G02I-12000J0D01*
G01X1332996D02*
G02I-6850J0D01*
G01X1326146Y-276199D02*
Y-244199D01*
X108200Y775800D03*
X112700Y775300D03*
Y770800D03*
X108200D03*
X103700D03*
Y775800D03*
Y766300D03*
X108200D03*
X112700D03*
X158170Y314302D03*
X162670D03*
X153670D03*
X156170Y318302D03*
X160670D03*
X224500Y170500D03*
Y174700D03*
Y166300D03*
Y178900D03*
X223000Y184000D03*
Y188500D03*
X225000Y192500D03*
X229200D03*
X259500Y138500D03*
X261500Y173500D03*
X253000Y166500D03*
X258700D03*
X262900D03*
X243000Y176500D03*
X243500Y166500D03*
Y162000D03*
Y157000D03*
X261500Y179000D03*
Y184500D03*
X261000Y190500D03*
X258225Y193963D03*
X266500Y184500D03*
Y190500D03*
X243000Y181000D03*
Y186000D03*
X239900Y600100D03*
X240000Y608600D03*
Y604400D03*
X271000Y184500D03*
X329500Y192500D03*
X328000Y197400D03*
X334500Y197500D03*
Y192500D03*
X344000Y197500D03*
X339500D03*
X344000Y192500D03*
X339500D03*
X536081Y304376D03*
X536809Y298789D03*
X565063Y256608D03*
Y247608D03*
Y252108D03*
X560318Y267199D03*
Y272199D03*
X560418Y278299D03*
Y283799D03*
Y289299D03*
X560318Y295699D03*
X553563Y306108D03*
Y310608D03*
X557904Y327115D03*
X562123Y319158D03*
X553455Y314807D03*
X553463Y319108D03*
X557863D03*
X605063Y257608D03*
X585515Y276459D03*
X583009Y264117D03*
X585351Y269292D03*
X587984Y246148D03*
X587980Y251975D03*
X589164Y264150D03*
X582738Y273300D03*
X587063Y257608D03*
X582976Y246148D03*
X583286Y251974D03*
X582682Y257614D03*
X589400Y308626D03*
X585737Y289608D03*
Y283108D03*
X582683Y279618D03*
X582411Y286589D03*
X582363Y293408D03*
X580563Y308608D03*
X583391Y298870D03*
X583282Y303091D03*
X611563Y278108D03*
X607563Y265608D03*
X607463Y270608D03*
X607563Y261108D03*
X609063Y255608D03*
X607563Y276108D03*
Y282108D03*
Y287608D03*
Y293608D03*
X607519Y299497D03*
X611563Y290108D03*
Y284608D03*
X666593Y226677D03*
X662593Y223677D03*
X658093D03*
X670063Y274708D03*
X669633Y259148D03*
X672100Y299800D03*
X704537Y221492D03*
X678063Y238108D03*
X673063D03*
X672927Y219677D03*
X677927D03*
X686063Y230108D03*
X696800Y237900D03*
X682763Y238008D03*
X686063Y224608D03*
X703600Y233700D03*
X687253Y237878D03*
X691753D03*
X698300Y226500D03*
X693800D03*
X689623Y269648D03*
X694963Y269608D03*
X689723Y274748D03*
X694223D03*
X679723D03*
X684223D03*
X690233Y255748D03*
X695000Y255800D03*
X690133Y260348D03*
X694633D03*
X680133Y259148D03*
X684633D03*
X674563Y274708D03*
X674133Y259148D03*
X695963Y302308D03*
Y297808D03*
Y293308D03*
X690663Y287608D03*
Y292108D03*
X677000Y299900D03*
X682063Y299108D03*
X683800Y295000D03*
X684063Y285908D03*
Y290408D03*
X712337Y207792D03*
X712137Y213292D03*
Y219392D03*
X725300Y228700D03*
X730300D03*
X711300D03*
X716300D03*
X716900Y233800D03*
X721400D03*
X730400D03*
X725900D03*
X735400D03*
X707900D03*
X712400D03*
X738800Y272000D03*
Y265500D03*
Y258000D03*
Y251500D03*
X706800Y272500D03*
Y265500D03*
Y258000D03*
Y252000D03*
X715300Y272000D03*
Y265500D03*
Y258000D03*
Y251500D03*
X724300Y272000D03*
Y265500D03*
Y258000D03*
Y251500D03*
X732300Y272000D03*
Y265500D03*
Y258000D03*
Y251500D03*
X706800Y290700D03*
X718800Y291000D03*
X714300D03*
X707363Y298108D03*
X718863Y295908D03*
X714363D03*
X723300Y291000D03*
X732300D03*
X727800D03*
X723363Y295908D03*
X732363D03*
X727863D03*
X737300Y291000D03*
X921300Y74700D03*
X918100Y71900D03*
X929464Y49420D03*
X925022Y42909D03*
X929713Y44849D03*
X926500Y60050D03*
X930500Y57500D03*
X976066Y26581D03*
X971466Y26681D03*
X975086Y61900D03*
X970000Y61050D03*
X985880Y41686D03*
X980566Y26581D03*
X985880Y46086D03*
Y50586D03*
X1177600Y241200D03*
X1173400D03*
X1166400Y234300D03*
X1170600D03*
X1175700D03*
X1171300Y215700D03*
X1166300D03*
X1175999D03*
X1177200Y248200D03*
X1173000D03*
X1177300Y254400D03*
X1173100D03*
X1176300Y261500D03*
X1171200D03*
X1167000D03*
X1168000Y280000D03*
X1173000D03*
X1177500D03*
X1203100Y241100D03*
X1198900D03*
X1207900D03*
X1182400Y241200D03*
X1197900Y234300D03*
X1207400D03*
X1203200D03*
X1179900D03*
X1188900D03*
X1184700D03*
X1193700D03*
X1190300Y215700D03*
X1185300D03*
X1208800D03*
X1203800D03*
X1180601D03*
X1199300D03*
X1194500D03*
X1182000Y248200D03*
X1202600Y254100D03*
X1198400D03*
X1207400D03*
X1202500Y247500D03*
X1198300D03*
X1207300D03*
X1182100Y254400D03*
X1203800Y261500D03*
X1208000D03*
X1194300D03*
X1198500D03*
X1185300D03*
X1189500D03*
X1180500D03*
X1187000Y280000D03*
X1192000D03*
X1205500D03*
X1210500D03*
X1182500D03*
X1201000D03*
X1196200D03*
X1229000Y210500D03*
X1242500Y209000D03*
X1232000Y194500D03*
X1237000D03*
X1226500Y201500D03*
Y194500D03*
X1244500D03*
X1212900Y234300D03*
X1214800Y215700D03*
X1233900Y240700D03*
X1239900D03*
X1244900D03*
X1228900D03*
X1228500Y235000D03*
X1234000D03*
X1240000D03*
X1245000D03*
X1214000Y261500D03*
X1233800Y246600D03*
X1239800D03*
X1244800D03*
X1228800D03*
X1229000Y252000D03*
X1245000D03*
X1240000D03*
X1234000D03*
X1227000Y279000D03*
X1242000D03*
X1232000Y292000D03*
X1237000D03*
X1227000Y285500D03*
X1244500Y292000D03*
X1247500Y209000D03*
X1252500Y194500D03*
X1263000Y210307D03*
X1257500Y194500D03*
X1263000Y202000D03*
X1262500Y194500D03*
X1255900Y240700D03*
X1249900D03*
X1262500Y235000D03*
X1250000D03*
X1256000D03*
X1255800Y246600D03*
X1249800D03*
X1262000Y252000D03*
X1256000D03*
X1250000D03*
X1247000Y279000D03*
X1262500Y279500D03*
X1252000Y292000D03*
X1257000D03*
X1262500Y286000D03*
X1327782Y192579D03*
Y200579D03*
Y207579D03*
X1328411Y237679D03*
X1327782Y215579D03*
Y221579D03*
X1327841Y228639D03*
X1332683Y240409D03*
X1328356Y242091D03*
X1328317Y246291D03*
X1332683Y244609D03*
Y248809D03*
X1326250Y669550D03*
X1366672Y210312D03*
X1360844Y210366D03*
X1355944Y210313D03*
X1351525Y207104D03*
X1351545Y202879D03*
Y198575D03*
X1378115Y189144D03*
X1374000Y192500D03*
Y188300D03*
Y196700D03*
X1378500Y198000D03*
X1378115Y193344D03*
X1375196Y217203D03*
X1367042Y223895D03*
X1375359Y230110D03*
X1372000Y240500D03*
X1351777Y227823D03*
X1360644Y223881D03*
X1350987Y236754D03*
X1351668Y232125D03*
X1355644Y223881D03*
X1351899Y219598D03*
X1351954Y215268D03*
X1354989Y239016D03*
X1350950Y241000D03*
X1349639Y211374D03*
X1349298Y223737D03*
X1372000Y245300D03*
Y249500D03*
X1355050Y247300D03*
X1350950Y246100D03*
X1382500Y193500D03*
Y188000D03*
G54D50*
X276700Y143300D03*
X626763Y238108D03*
X647000Y788200D03*
X946600Y44100D03*
X1313100Y266500D03*
X1363500Y254500D03*
G54D41*
X115355Y887970D03*
X118504D03*
X121654D03*
X124803D03*
X127953D03*
X131103D03*
X134252D03*
X137402D03*
X140551D03*
X143701D03*
X146851D03*
X150000D03*
X153150D03*
X156300D03*
X159449D03*
X162599D03*
X165748D03*
X168898D03*
X172048D03*
X175197D03*
X178347D03*
X181496D03*
X184646D03*
X187796D03*
X190945D03*
X194095D03*
X197244D03*
X200394D03*
X203544D03*
X206693D03*
X209843D03*
X212992D03*
X216142D03*
X219292D03*
X222441D03*
X225591D03*
X228740D03*
X231890D03*
X235040D03*
X238189D03*
X241339D03*
X244488D03*
X247638D03*
X250788D03*
X253937D03*
X257087D03*
X260237D03*
X263386D03*
X266536D03*
X269685D03*
X272835D03*
X275985D03*
X279134D03*
X282284D03*
X285433D03*
X288583D03*
X304331D03*
X307481D03*
X310630D03*
X313780D03*
X316929D03*
X320079D03*
X323229D03*
X326378D03*
X329528D03*
X332677D03*
X335827D03*
X338977D03*
X342126D03*
X345276D03*
X348426D03*
X351575D03*
X354725D03*
X357874D03*
X361024D03*
X364174D03*
X367323D03*
X370473D03*
X373622D03*
X376772D03*
X379922D03*
X383071D03*
X386221D03*
X389370D03*
X392520D03*
X395670D03*
X398819D03*
X401969D03*
X405118D03*
X408268D03*
X411418D03*
X414567D03*
X417717D03*
X420866D03*
X424016D03*
X427166D03*
X430315D03*
X433465D03*
X436614D03*
X439764D03*
X532678D03*
X535827D03*
X538977D03*
X542126D03*
X545276D03*
X548426D03*
X551575D03*
X554725D03*
X557874D03*
X561024D03*
X564174D03*
X567323D03*
X570473D03*
X573623D03*
X576772D03*
X579922D03*
X583071D03*
X586221D03*
X589371D03*
X592520D03*
X595670D03*
X598819D03*
X601969D03*
X605119D03*
X608268D03*
X611418D03*
X614567D03*
X617717D03*
X620867D03*
X624016D03*
X627166D03*
X630315D03*
X633465D03*
X636615D03*
X639764D03*
X642914D03*
X646063D03*
X649213D03*
X652363D03*
X655512D03*
X658662D03*
X661811D03*
X664961D03*
X668111D03*
X671260D03*
X674410D03*
X677560D03*
X680709D03*
X683859D03*
X687008D03*
X690158D03*
X693308D03*
X696457D03*
X699607D03*
X702756D03*
X705906D03*
X721654D03*
X724804D03*
X727953D03*
X731103D03*
X734252D03*
X737402D03*
X740552D03*
X743701D03*
X746851D03*
X750000D03*
X753150D03*
X756300D03*
X759449D03*
X762599D03*
X765749D03*
X768898D03*
X772048D03*
X775197D03*
X778347D03*
X781497D03*
X784646D03*
X787796D03*
X790945D03*
X794095D03*
X797245D03*
X800394D03*
X803544D03*
X806693D03*
X809843D03*
X812993D03*
X816142D03*
X819292D03*
X822441D03*
X825591D03*
X828741D03*
X831890D03*
X835040D03*
X838189D03*
X841339D03*
X844489D03*
X847638D03*
X850788D03*
X853937D03*
X857087D03*
X1028741D03*
X1031890D03*
X1035040D03*
X1038189D03*
X1041339D03*
X1044489D03*
X1047638D03*
X1050788D03*
X1053937D03*
X1057087D03*
X1060237D03*
X1063386D03*
X1066536D03*
X1069686D03*
X1072835D03*
X1075985D03*
X1079134D03*
X1082284D03*
X1085434D03*
X1088583D03*
X1091733D03*
X1094882D03*
X1098032D03*
X1101182D03*
X1104331D03*
X1107481D03*
X1110630D03*
X1113780D03*
X1116930D03*
X1120079D03*
X1123229D03*
X1126378D03*
X1129528D03*
X1132678D03*
X1135827D03*
X1138977D03*
X1142126D03*
X1145276D03*
X1148426D03*
X1151575D03*
X1154725D03*
X1157874D03*
X1161024D03*
X1164174D03*
X1167323D03*
X1170473D03*
X1173623D03*
X1176772D03*
X1179922D03*
X1183071D03*
X1186221D03*
X1189371D03*
X1192520D03*
X1195670D03*
X1198819D03*
X1201969D03*
X1217717D03*
X1220867D03*
X1224016D03*
X1227166D03*
X1230315D03*
X1233465D03*
X1236615D03*
X1239764D03*
X1242914D03*
X1246063D03*
X1249213D03*
X1252363D03*
X1255512D03*
X1258662D03*
X1261812D03*
X1264961D03*
X1268111D03*
X1271260D03*
X1274410D03*
X1277560D03*
X1280709D03*
X1283859D03*
X1287008D03*
X1290158D03*
X1293308D03*
X1296457D03*
X1299607D03*
X1302756D03*
X1305906D03*
X1309056D03*
X1312205D03*
X1315355D03*
X1318504D03*
X1321654D03*
X1324804D03*
X1327953D03*
X1331103D03*
X1334252D03*
X1337402D03*
X1340552D03*
X1343701D03*
X1346851D03*
X1350000D03*
X1353150D03*
G54D32*
X72900Y733100D03*
X148500Y525300D03*
X158500Y526300D03*
X221000Y521800D03*
X294500Y149300D03*
X290178Y736231D03*
X273500Y736200D03*
X322178Y736231D03*
X306178D03*
X503178Y788231D03*
X487000Y788200D03*
X488500Y811800D03*
X535178Y788231D03*
X519069Y788767D03*
X556531Y364880D03*
X560531D03*
X635500Y366900D03*
X645663Y238308D03*
X639000Y366900D03*
X847500Y765700D03*
X862678Y765731D03*
X892678Y765231D03*
X1204335Y138491D03*
X1207745Y138490D03*
X1266432Y154937D03*
X1269834D03*
X1307400Y693700D03*
X1306000Y716800D03*
X1324900Y693700D03*
X1341400D03*
G54D23*
X57700Y499200D03*
X53600D03*
X92360Y566710D03*
X110000Y291200D03*
X145000Y461700D03*
X141000D03*
X150150Y452690D03*
X155680Y452630D03*
X146150Y452690D03*
X137000Y461200D03*
X140500Y452690D03*
X164000Y461200D03*
X161500Y501700D03*
X164000Y795200D03*
X160000D03*
X182300Y411300D03*
X193650Y458522D03*
X189650D03*
X197500Y574200D03*
X191500Y584700D03*
X199500Y716200D03*
X171300Y739500D03*
X167300D03*
X199500Y771700D03*
X200500Y411700D03*
X230571Y469717D03*
X221000Y538200D03*
X229000Y521700D03*
X225000Y529200D03*
X229000D03*
X201500Y574200D03*
X203500Y716200D03*
Y771700D03*
X237500Y135700D03*
X245500D03*
X241500D03*
X235100Y466200D03*
X251800Y466400D03*
X274406Y723098D03*
X278406D03*
X286906Y772098D03*
X299164Y772291D03*
X295079Y772050D03*
X303406Y772098D03*
X323406Y771098D03*
X319406D03*
X476200Y380400D03*
X480200D03*
X487906Y775098D03*
X491906D03*
X500406Y824098D03*
X512679Y824050D03*
X508579D03*
X516906Y824098D03*
X524906D03*
X528906D03*
X711510Y13880D03*
X715380Y25480D03*
X715130Y49100D03*
X837000Y778200D03*
X852400Y87500D03*
X871000Y82200D03*
X848100Y87600D03*
X856906Y752098D03*
X860906D03*
X869906Y801098D03*
X893100Y38100D03*
X875000Y93200D03*
X879500D03*
X884000D03*
X888500D03*
X893000D03*
X897500D03*
X902000D03*
X906500D03*
X882049Y803660D03*
X877949D03*
X886276Y803708D03*
X894406Y801098D03*
X898406D03*
X911000Y93200D03*
X915500D03*
X920000D03*
X933500D03*
X929000D03*
X924500D03*
X938000D03*
X956000D03*
X990552Y104500D03*
X986552D03*
X1003100D03*
X999000D03*
X987039Y157215D03*
X1040140Y10963D03*
X1035830Y10919D03*
X1044147Y13790D03*
X1049161Y11807D03*
X1073250Y32450D03*
X1046950Y36565D03*
X1051450D03*
X1068750Y20450D03*
X1065475Y52273D03*
X1061342Y75796D03*
X1293500Y277700D03*
X1302128Y680567D03*
X1306128D03*
X1314628Y729567D03*
X1325500Y729700D03*
X1334128Y729567D03*
X1338128D03*
X1355000Y283200D03*
X1359000D03*
X1351000D03*
G54D14*
X29000Y616000D03*
X63500Y353960D03*
X54903Y447003D03*
X68100Y264700D03*
X98588Y281650D03*
X96304Y287616D03*
X70124Y279374D03*
X78500Y277900D03*
X92907Y280765D03*
X67796Y470042D03*
X86363Y479563D03*
X95742Y490870D03*
X86787Y494553D03*
X66854Y507824D03*
X68600Y494400D03*
X88700Y524900D03*
X88565Y532410D03*
X70515Y538726D03*
X68567Y531405D03*
X88278Y548853D03*
X73100Y553100D03*
X88338Y553955D03*
X85500Y807700D03*
X116906Y283244D03*
X111000Y324200D03*
X102457Y347690D03*
X132204Y434627D03*
X114818Y433528D03*
X128280Y476120D03*
X105728Y471628D03*
X103500Y465026D03*
X127142Y459404D03*
X107889Y457989D03*
X116204Y474504D03*
X131718Y498682D03*
X128450Y481470D03*
X117771Y499896D03*
X117867Y488950D03*
X128100Y507700D03*
X100063Y498972D03*
X103055Y503417D03*
X106818Y513350D03*
X99221Y509408D03*
X106037Y507711D03*
X106900Y488923D03*
X114000Y483700D03*
X105555Y483119D03*
X116439Y547024D03*
X102075Y529701D03*
X130200Y517000D03*
X106575Y518876D03*
X107341Y528856D03*
X99768Y518303D03*
X113757Y520886D03*
X105136Y535172D03*
X113900Y533666D03*
X102326Y540322D03*
X100270Y545196D03*
X122048Y541693D03*
X115100Y541700D03*
X123100Y547800D03*
X100350Y550196D03*
X105851Y637000D03*
X120500Y697500D03*
X122167Y731990D03*
X99700Y732300D03*
X103800Y727700D03*
X110900Y779200D03*
X122200Y831700D03*
X134587Y443980D03*
X137136Y422798D03*
X165000Y468000D03*
X157500D03*
X139500Y466500D03*
X134500Y466000D03*
X157500Y458000D03*
Y463000D03*
X133440Y449150D03*
X132959Y460709D03*
X159434Y475345D03*
X133589Y477613D03*
X136272Y496478D03*
X137600Y501338D03*
X150100Y494700D03*
X164371Y494680D03*
X165864Y533933D03*
X143500Y622500D03*
X137194Y727551D03*
X164378Y778459D03*
X159774Y785777D03*
X164442Y802359D03*
X159838Y813369D03*
X148000Y833500D03*
X175430Y261054D03*
X173277Y315920D03*
X167423Y341376D03*
X188215Y333962D03*
X182855Y337950D03*
X176854Y332347D03*
X187361Y342183D03*
X181838Y332783D03*
X178692Y352383D03*
X197937Y384347D03*
X197713Y431418D03*
X199900Y420100D03*
X175317Y416683D03*
X181400Y415300D03*
X182000Y466000D03*
X177000D03*
X171000Y468000D03*
X169000Y463000D03*
Y458000D03*
X187928Y473629D03*
X179192Y471349D03*
X190675Y468551D03*
X181328Y460701D03*
X199880Y498149D03*
X198000Y493500D03*
X166608Y501664D03*
X184535Y502910D03*
X194148Y501205D03*
X187300Y486900D03*
X169514Y492829D03*
X199809Y485199D03*
X178000Y542000D03*
X173000Y547500D03*
X178000Y547000D03*
X167000Y545500D03*
X168599Y527221D03*
X173000Y542500D03*
X173618Y516881D03*
X181811Y524978D03*
X188978Y524513D03*
X185355Y537874D03*
X173000Y552500D03*
X193600Y569800D03*
X186416Y573231D03*
X193500Y628000D03*
X199379Y698698D03*
X171631Y722694D03*
X167027Y730499D03*
X199411Y721528D03*
X171729Y747695D03*
X199378Y752617D03*
X167125Y759093D03*
X199410Y790376D03*
X169840Y836660D03*
X174265Y828735D03*
X220384Y178059D03*
X215968Y389018D03*
X214888Y425445D03*
X221699Y428056D03*
X202469Y429873D03*
X205100Y413700D03*
X202185Y462653D03*
X204319Y479895D03*
X206487Y475373D03*
X218774Y452245D03*
X224548Y470077D03*
X206285Y457550D03*
X218425D03*
X223334Y458504D03*
X210828Y469403D03*
X205397Y489870D03*
X232600Y535000D03*
X201400Y532400D03*
X205000Y521500D03*
X217291Y524970D03*
X201900Y525500D03*
X222500Y514500D03*
X222700Y546500D03*
X206200Y530500D03*
X201429Y566997D03*
X222800Y562100D03*
X210510Y562800D03*
X203983Y706502D03*
X204015Y733445D03*
X204186Y762392D03*
X204014Y779192D03*
X217104Y796396D03*
X214649Y802351D03*
X212841Y807659D03*
X218937Y791063D03*
X249530Y132250D03*
X236807Y140322D03*
X236500Y147500D03*
X239500Y160500D03*
X266200Y243500D03*
X251700Y429200D03*
X241446Y452004D03*
X247661Y473600D03*
X247473Y455600D03*
X260500Y486800D03*
X259800Y492500D03*
X233701Y522611D03*
X262500Y532012D03*
X241521Y654021D03*
X248890Y708110D03*
X255968Y706032D03*
X249797Y701703D03*
X259633Y715867D03*
X260816Y710184D03*
X254212Y712288D03*
X267011Y718817D03*
X257728Y722272D03*
X263500Y748700D03*
X268500Y140500D03*
X273800Y240000D03*
X299800Y305500D03*
X285700Y578165D03*
X285900Y583165D03*
X285606Y588172D03*
X267540Y585155D03*
X273134Y593265D03*
X270430Y725738D03*
X279045Y729078D03*
X293738Y729123D03*
X299500Y736000D03*
X283004Y739009D03*
X278500Y768500D03*
X290830Y768755D03*
X285000Y757000D03*
X297500D03*
X275900Y755951D03*
X334755Y141755D03*
X321708Y371677D03*
X321454Y351196D03*
X330000Y496213D03*
X329913Y714413D03*
X321500Y706500D03*
X328331Y708331D03*
X306471Y722269D03*
X318162Y729949D03*
X302000Y730500D03*
X332500Y739500D03*
X315531Y734807D03*
X307400Y765738D03*
X327373Y765761D03*
X317453Y752192D03*
X303000Y756500D03*
X329575Y758230D03*
X315100Y757400D03*
X359061Y335014D03*
X338725Y481514D03*
X357500Y561500D03*
X362533Y808033D03*
X364759Y815759D03*
X360807Y799807D03*
X417988Y813088D03*
X449500Y85000D03*
X480533Y363869D03*
X475782Y371442D03*
X480960Y388964D03*
X476010Y399971D03*
X485724Y779993D03*
X495307Y763932D03*
X495824Y756449D03*
X487949Y760641D03*
X487744Y752436D03*
X498500Y809000D03*
X477000Y804000D03*
X481600Y796800D03*
X496000Y788000D03*
X492278Y820500D03*
X481000Y818000D03*
X520910Y124390D03*
X515220Y126440D03*
X531900Y155800D03*
X523242Y196195D03*
X529154Y255014D03*
X525785Y362796D03*
X537000Y700500D03*
X504169Y774643D03*
X518328Y781467D03*
X531500Y778600D03*
X514298Y784745D03*
X516500Y808000D03*
X530012Y803025D03*
X510500Y808500D03*
X527948Y809620D03*
X508700Y784700D03*
X528500Y788000D03*
X521000Y820000D03*
X504241Y820278D03*
X532506Y820000D03*
X538158Y156255D03*
X546391Y208718D03*
X548656Y229162D03*
X568663Y288740D03*
X554300Y368300D03*
X545500Y783500D03*
X537500Y817000D03*
X546200Y799800D03*
X546000Y793000D03*
X577336Y125424D03*
X573055Y121869D03*
X603163Y220858D03*
X580200Y224000D03*
X596500Y226100D03*
X591861Y232396D03*
X576200Y238400D03*
X602463Y284008D03*
X616614Y123871D03*
X611642Y123340D03*
X607812Y149121D03*
X612812Y149084D03*
X609777Y158860D03*
X632900Y339700D03*
X655000Y125360D03*
X649692Y125160D03*
X643518Y125457D03*
X656500Y139300D03*
X670465Y266585D03*
X646600Y363400D03*
X643538Y803500D03*
X641000Y816500D03*
X646800Y811500D03*
X691100Y168238D03*
X691400Y310000D03*
X691487Y798987D03*
X693243Y804943D03*
X688212Y791912D03*
X695049Y811349D03*
X731800Y166000D03*
X706937Y203092D03*
X736100Y197200D03*
X741600Y34439D03*
X751871Y175034D03*
X755200Y223800D03*
X756200Y299800D03*
X799459Y772175D03*
X815976Y32276D03*
X838881Y27195D03*
X833246Y24741D03*
X826141Y21594D03*
X819052Y23633D03*
X811937Y41381D03*
X827727Y43554D03*
X825500Y697000D03*
X817405Y779905D03*
X808584Y776584D03*
X831500Y774750D03*
X836300Y783300D03*
X865600Y-1700D03*
X853500Y-2100D03*
X863500Y28000D03*
X848545Y24961D03*
X843545Y25012D03*
X871800Y15309D03*
X850900Y16200D03*
X848623Y74557D03*
X865004Y49379D03*
X866000Y82500D03*
X859000Y86500D03*
X866919Y92419D03*
X858821Y75500D03*
X853500Y257000D03*
X850799Y743301D03*
X872500Y728500D03*
X844500Y750000D03*
X851500Y753000D03*
X872617Y750235D03*
X864366Y758100D03*
X856576Y767771D03*
X867640Y761880D03*
X861500Y797000D03*
X853500Y817362D03*
X874033Y797475D03*
X864000Y814500D03*
X858020Y786180D03*
X840960Y785260D03*
X864147Y785093D03*
X863500Y823338D03*
X845500Y820500D03*
X878320Y4350D03*
X888200Y30500D03*
X882429Y54551D03*
X905488Y48573D03*
X902169Y97919D03*
X894533Y100933D03*
X875070Y104670D03*
X894850Y112060D03*
X903920Y137780D03*
X898000Y117000D03*
X908020Y153340D03*
X903937Y145666D03*
X903970Y157478D03*
X895232Y186459D03*
X885000Y297000D03*
X898500Y499000D03*
X880889Y613611D03*
X875252Y623748D03*
X896000Y686000D03*
X884700Y708000D03*
X892100Y694000D03*
X881200Y713500D03*
X888550Y702000D03*
X887500Y731500D03*
X879815Y742296D03*
X886800Y759500D03*
X878578Y761050D03*
X899800Y753000D03*
X898566Y761430D03*
X886500Y765000D03*
X890500Y796638D03*
X888000Y789000D03*
X874800Y786800D03*
X900000Y786000D03*
X882590Y787130D03*
X925300Y47100D03*
X910945Y49234D03*
X938600Y99500D03*
X915315Y97565D03*
X939384Y106513D03*
X915926Y102676D03*
X908676Y99926D03*
X911800Y141750D03*
X919650Y137800D03*
X915750Y133900D03*
X912200Y112300D03*
X940051Y113222D03*
X934700Y114200D03*
X911817Y149617D03*
X911820Y157500D03*
X915790Y161420D03*
X919685Y149606D03*
X915750Y145650D03*
Y153500D03*
X919700Y157500D03*
X927559Y153543D03*
X920800Y143400D03*
X923620Y161450D03*
X914700Y281100D03*
X947000Y71500D03*
X960244Y64888D03*
X952900Y98900D03*
X967263Y100000D03*
Y105000D03*
X975004Y105097D03*
Y100097D03*
X960500Y105000D03*
X953000Y104500D03*
X944300Y98500D03*
X960500Y100000D03*
X960000Y95000D03*
X959793Y75788D03*
X970866Y137795D03*
X974803Y141732D03*
X949700Y112900D03*
X959055Y129921D03*
X974803Y133858D03*
X966929D03*
X955118Y141732D03*
X959055Y137795D03*
X949987Y131571D03*
X948058Y136248D03*
X974803Y157480D03*
X970866Y161417D03*
X955118Y149606D03*
X959055Y145669D03*
X970866Y153543D03*
X966929Y149606D03*
X970866Y145669D03*
X959055Y161417D03*
Y153543D03*
X962992Y157480D03*
X951181Y153543D03*
X945030Y156121D03*
X944300Y271000D03*
X968500Y383500D03*
X1005774Y31854D03*
X1005750Y19788D03*
X980000Y44000D03*
X996251Y45701D03*
X982000Y100000D03*
Y105000D03*
X994700Y108600D03*
X982677Y141732D03*
X990551Y133858D03*
X982677D03*
X984760Y112189D03*
X982700Y149600D03*
X978740Y153543D03*
X982632Y157480D03*
X978740Y161417D03*
X991300Y145800D03*
X991608Y153979D03*
X1000000Y187000D03*
X980000Y281300D03*
X1035323Y-758D03*
X1031991Y22473D03*
X1036989Y22307D03*
X1036013Y27318D03*
X1033971Y34914D03*
X1031474Y9728D03*
X1020676Y53563D03*
X1037815Y104700D03*
X1016500Y101050D03*
X1041249Y112300D03*
X1030883Y112238D03*
X1066272Y1949D03*
X1044391Y-1209D03*
X1069394Y13018D03*
X1052744Y48446D03*
X1072167Y49782D03*
X1069889Y45154D03*
X1048000Y815000D03*
X1088503Y3601D03*
X1085500Y-3000D03*
X1086715Y27686D03*
X1080017Y27022D03*
X1086500Y280000D03*
X1167000Y254000D03*
X1171747Y814500D03*
X1176738Y806500D03*
X1168607Y834500D03*
X1198134Y420766D03*
X1179723Y418777D03*
X1242500Y645000D03*
X1236000Y814000D03*
X1269500Y161000D03*
X1261000Y230000D03*
X1255000Y323000D03*
X1274030Y339470D03*
X1264820Y356000D03*
X1273500Y406500D03*
X1270000Y487500D03*
X1269000Y609000D03*
X1284505Y308395D03*
X1280836Y338164D03*
X1295000Y338000D03*
X1307500Y340500D03*
X1293280Y345770D03*
X1289960Y349900D03*
X1299000Y347500D03*
X1298500Y376500D03*
X1312839Y384339D03*
X1305500Y379500D03*
X1305432Y622932D03*
X1296264Y645191D03*
X1291800Y637751D03*
X1292000Y667000D03*
X1298017Y684000D03*
X1303709Y688956D03*
X1298000Y703500D03*
X1298500Y734838D03*
X1305650Y725500D03*
X1295714Y716714D03*
X1327736Y271358D03*
X1325500Y289400D03*
X1314422Y638422D03*
X1318117Y680886D03*
X1343000Y681000D03*
X1331000Y658200D03*
X1330000Y672162D03*
X1333052Y686020D03*
X1319500Y690000D03*
X1337338Y712709D03*
X1322300Y713500D03*
X1315000Y714000D03*
X1333639Y716074D03*
X1317500Y695000D03*
X1334195Y694005D03*
X1318228Y725500D03*
X1330000Y724500D03*
X1344237Y721833D03*
X1342000Y726500D03*
X1338128Y738000D03*
X1320500Y719888D03*
X1324000Y763500D03*
X1340500Y751500D03*
X1379473Y163528D03*
X1368540Y169284D03*
X1353908Y194867D03*
X1365804Y189733D03*
X1370000Y216500D03*
X1354500Y271000D03*
X1355209Y263791D03*
X1364000Y299500D03*
X1351500Y671200D03*
X1355000Y716000D03*
X1352000Y708500D03*
Y698000D03*
X1353500Y758500D03*
X1383164Y168943D03*
G54D42*
X162200Y512500D03*
Y509000D03*
Y505500D03*
X162219Y521720D03*
X162200Y516000D03*
X181700Y443300D03*
X612263Y253108D03*
X639700Y355600D03*
Y359600D03*
X874348Y764898D03*
X1005412Y35919D03*
G54D51*
X273162Y749719D03*
X275722D03*
X278282D03*
Y743219D03*
X273162D03*
X290440Y749750D03*
X293000D03*
X295560D03*
Y743250D03*
X290440D03*
X306440Y749750D03*
X309000D03*
X311560D03*
Y743250D03*
X306440D03*
X322440Y749750D03*
X325000D03*
X327560D03*
Y743250D03*
X322440D03*
X486662Y801719D03*
X489222D03*
X491782D03*
Y795219D03*
X486662D03*
X535440Y801750D03*
Y795250D03*
X519440Y801750D03*
X522000D03*
X524560D03*
Y795250D03*
X519440D03*
X503440Y801750D03*
X506000D03*
X508560D03*
Y795250D03*
X503440D03*
X538000Y801750D03*
X540560D03*
Y795250D03*
X873060Y37350D03*
X870500D03*
X867940D03*
Y43850D03*
X873060D03*
X862940Y778750D03*
X865500D03*
X868060D03*
Y772250D03*
X862940D03*
X846662Y779219D03*
X849222D03*
X851782D03*
Y772719D03*
X846662D03*
X892940Y778750D03*
X895500D03*
X898060D03*
Y772250D03*
X892940D03*
X876940Y778750D03*
X879500D03*
X882060D03*
Y772250D03*
X876940D03*
X1307662Y706719D03*
X1310222D03*
X1307662Y700219D03*
X1312782Y706719D03*
Y700219D03*
X1341662Y707219D03*
X1344222D03*
X1341662Y700719D03*
X1325162Y707219D03*
X1327722D03*
X1330282D03*
Y700719D03*
X1325162D03*
X1376734Y175745D03*
X1374174D03*
X1371614D03*
Y182245D03*
X1376734D03*
X1346782Y707219D03*
Y700719D03*
G54D15*
X39370Y801181D03*
X336417Y21260D03*
X293110Y55906D03*
X336417Y90551D03*
X789850Y236220D03*
Y283464D03*
X1376968Y21260D03*
X1333661Y55906D03*
X1360630Y135826D03*
Y801181D03*
X1376968Y90551D03*
G54D60*
X897500Y141714D03*
X895300D03*
X897500Y137800D03*
X895300D03*
X897500Y133877D03*
X895300D03*
X897500Y129903D03*
X895300D03*
X897500Y153562D03*
X895300D03*
X897500Y149600D03*
X895300D03*
X897500Y145688D03*
X895300D03*
X897500Y161436D03*
X895300D03*
X897500Y157499D03*
X895300D03*
X893100Y236200D03*
X890900D03*
X936300Y129900D03*
X934100D03*
X911900Y137800D03*
X909700D03*
X925850Y149620D03*
X923650D03*
X926700Y165338D03*
X924500D03*
X912900Y181100D03*
X910700D03*
X926700Y185168D03*
X924500D03*
X926700Y204700D03*
X924500D03*
X934800D03*
X932600D03*
X940500D03*
X939500Y224400D03*
Y232300D03*
X936600Y236210D03*
X934400D03*
X928600D03*
X926400D03*
X936600Y228327D03*
X934400D03*
X936600Y220480D03*
X934400D03*
X928600D03*
X926400D03*
X912900Y216500D03*
X910700D03*
X928600Y228327D03*
X926400D03*
X926700Y212600D03*
X924500D03*
X934800D03*
X932600D03*
X955200Y137800D03*
X953000D03*
X951000Y149600D03*
X948800D03*
X954368Y161468D03*
X952168D03*
X954368Y157468D03*
X952168D03*
X966200Y165338D03*
X964000D03*
X974000D03*
X971800D03*
X958300Y173218D03*
X956100D03*
X966200D03*
X964000D03*
X974000D03*
X971800D03*
X958300Y165338D03*
X956100D03*
X950300D03*
X948100D03*
X950300Y173218D03*
X948100D03*
X973900Y177150D03*
X966200Y185168D03*
X964000D03*
X974000D03*
X971800D03*
X958300Y192900D03*
X956100D03*
X966200D03*
X964000D03*
X974000D03*
X971800D03*
X942700Y204700D03*
X973850Y216510D03*
X941700Y224400D03*
Y232300D03*
X960100Y224400D03*
X957900D03*
X952300D03*
X950100D03*
X968000D03*
X965800D03*
X952300Y232300D03*
X950100D03*
X960100D03*
X957900D03*
X968000D03*
X965800D03*
X995600Y161400D03*
X993400D03*
X995600Y169268D03*
X993400D03*
X995600Y173268D03*
X993400D03*
X995500Y157500D03*
X993300D03*
X991600Y165400D03*
X989400D03*
X995600Y177168D03*
X993400D03*
X995600Y181068D03*
X993400D03*
X990600Y185500D03*
X988400D03*
X995600Y188968D03*
X993400D03*
X995600Y192868D03*
X993400D03*
X995600Y196868D03*
X993400D03*
X976100Y177150D03*
X995600Y208668D03*
X993400D03*
X995600Y200768D03*
X993400D03*
X995600Y204668D03*
X993400D03*
X995600Y224368D03*
X993400D03*
X976050Y216510D03*
X995600Y228368D03*
X993400D03*
X995600Y212568D03*
X993400D03*
X995600Y216518D03*
X993400D03*
X995600Y220468D03*
X993400D03*
X995600Y236200D03*
X993400D03*
X995600Y232268D03*
X993400D03*
G54D24*
X57700Y495800D03*
X53600D03*
X92360Y563310D03*
X110000Y287800D03*
X145000Y458300D03*
X141000D03*
X150150Y449290D03*
X155680Y449230D03*
X146150Y449290D03*
X137000Y457800D03*
X140500Y449290D03*
X164000Y457800D03*
X161500Y498300D03*
X164000Y791800D03*
X160000D03*
X182300Y407900D03*
X193650Y455122D03*
X189650D03*
X197500Y570800D03*
X191500Y581300D03*
X199500Y712800D03*
X171300Y736100D03*
X167300D03*
X199500Y768300D03*
X200500Y408300D03*
X230571Y466317D03*
X221000Y534800D03*
X229000Y518300D03*
X225000Y525800D03*
X229000D03*
X201500Y570800D03*
X203500Y712800D03*
Y768300D03*
X237500Y132300D03*
X245500D03*
X241500D03*
X235100Y462800D03*
X251800Y463000D03*
X274406Y719698D03*
X278406D03*
X286906Y768698D03*
X299164Y768891D03*
X295079Y768650D03*
X303406Y768698D03*
X323406Y767698D03*
X319406D03*
X476200Y377000D03*
X480200D03*
X487906Y771698D03*
X491906D03*
X500406Y820698D03*
X512679Y820650D03*
X508579D03*
X516906Y820698D03*
X524906D03*
X528906D03*
X711510Y10480D03*
X715380Y22080D03*
X715130Y45700D03*
X837000Y774800D03*
X852400Y84100D03*
X871000Y78800D03*
X848100Y84200D03*
X856906Y748698D03*
X860906D03*
X869906Y797698D03*
X893100Y34700D03*
X875000Y89800D03*
X879500D03*
X884000D03*
X888500D03*
X893000D03*
X897500D03*
X902000D03*
X906500D03*
X882049Y800260D03*
X877949D03*
X886276Y800308D03*
X894406Y797698D03*
X898406D03*
X911000Y89800D03*
X915500D03*
X920000D03*
X933500D03*
X929000D03*
X924500D03*
X938000D03*
X956000D03*
X990552Y101100D03*
X986552D03*
X1003100D03*
X999000D03*
X987039Y153815D03*
X1035830Y7519D03*
X1040140Y7563D03*
X1044147Y10390D03*
X1049161Y8407D03*
X1073250Y29050D03*
X1046950Y33165D03*
X1051450D03*
X1068750Y17050D03*
X1065475Y48873D03*
X1061342Y72396D03*
X1293500Y274300D03*
X1302128Y677167D03*
X1306128D03*
X1314628Y726167D03*
X1325500Y726300D03*
X1334128Y726167D03*
X1338128D03*
X1355000Y279800D03*
X1359000D03*
X1351000D03*
G54D33*
X72900Y729500D03*
X148500Y521700D03*
X158500Y522700D03*
X221000Y518200D03*
X294500Y145700D03*
X290178Y732631D03*
X273500Y732600D03*
X322178Y732631D03*
X306178D03*
X503178Y784631D03*
X487000Y784600D03*
X488500Y808200D03*
X535178Y784631D03*
X519069Y785167D03*
X556531Y361280D03*
X560531D03*
X635500Y363300D03*
X645663Y234708D03*
X639000Y363300D03*
X847500Y762100D03*
X862678Y762131D03*
X892678Y761631D03*
X1204335Y134891D03*
X1207745Y134890D03*
X1266432Y151337D03*
X1269834D03*
X1307400Y690100D03*
X1306000Y713200D03*
X1324900Y690100D03*
X1341400D03*
G54D70*
G01X145579Y-328699D02*
Y-346199D01*
X154313D01*
G01X167446Y-334533D02*
Y-346199D01*
G01Y-329866D02*
X167009Y-329574D01*
Y-328991D01*
X167446Y-328699D01*
X167883Y-328991D01*
Y-329574D01*
X167446Y-329866D01*
G01X181889Y-350574D02*
X183418Y-351741D01*
X185164Y-352032D01*
X186692Y-351741D01*
X188003Y-350283D01*
X188876Y-348241D01*
Y-334533D01*
G01Y-336866D02*
X188003Y-335699D01*
X186692Y-334824D01*
X185164Y-334533D01*
X183418Y-335116D01*
X182326Y-336282D01*
X181452Y-338324D01*
X181016Y-340366D01*
X181234Y-342116D01*
X182108Y-344158D01*
X183418Y-345616D01*
X185164Y-346199D01*
X186474Y-345907D01*
X188003Y-344741D01*
X188876Y-343575D01*
G01X198734Y-346199D02*
Y-328699D01*
G01Y-337157D02*
X199826Y-335699D01*
X200918Y-334824D01*
X202664Y-334533D01*
X203974Y-334824D01*
X205503Y-335991D01*
X206158Y-337741D01*
Y-346199D01*
G01X219946Y-328699D02*
Y-346199D01*
G01X216889Y-334533D02*
X223003D01*
G01X233734Y-346199D02*
Y-334533D01*
G01Y-337449D02*
X234608Y-335991D01*
X235918Y-334824D01*
X237664Y-334533D01*
X239192Y-334824D01*
X240503Y-335991D01*
X241158Y-338032D01*
Y-346199D01*
G01X254946Y-334533D02*
Y-346199D01*
G01Y-329866D02*
X254509Y-329574D01*
Y-328991D01*
X254946Y-328699D01*
X255383Y-328991D01*
Y-329574D01*
X254946Y-329866D01*
G01X268734Y-346199D02*
Y-334533D01*
G01Y-337449D02*
X269608Y-335991D01*
X270918Y-334824D01*
X272664Y-334533D01*
X274192Y-334824D01*
X275503Y-335991D01*
X276158Y-338032D01*
Y-346199D01*
G01X286889Y-350574D02*
X288418Y-351741D01*
X290164Y-352032D01*
X291692Y-351741D01*
X293003Y-350283D01*
X293876Y-348241D01*
Y-334533D01*
G01Y-336866D02*
X293003Y-335699D01*
X291692Y-334824D01*
X290164Y-334533D01*
X288418Y-335116D01*
X287326Y-336282D01*
X286452Y-338324D01*
X286016Y-340366D01*
X286234Y-342116D01*
X287108Y-344158D01*
X288418Y-345616D01*
X290164Y-346199D01*
X291474Y-345907D01*
X293003Y-344741D01*
X293876Y-343575D01*
G01X320579Y-346199D02*
Y-328699D01*
X325819D01*
X327566Y-329574D01*
X328876Y-331616D01*
X329313Y-333949D01*
X328876Y-336282D01*
X327784Y-338032D01*
X325819Y-338908D01*
X320579D01*
G01X346813Y-346199D02*
X338079D01*
Y-328699D01*
X346813D01*
G01X343319Y-337157D02*
X338079D01*
G01X361692Y-336866D02*
X362566Y-335991D01*
X363221Y-334533D01*
X363658Y-332490D01*
X363221Y-330741D01*
X362348Y-329574D01*
X360819Y-328699D01*
X354924D01*
Y-346199D01*
X362129D01*
X363658Y-345033D01*
X364531Y-343282D01*
X364968Y-341241D01*
X364531Y-339199D01*
X363221Y-337449D01*
X361692Y-336866D01*
X354924D01*
G01X390579Y-346199D02*
Y-328699D01*
X395819D01*
X397566Y-329574D01*
X398876Y-331616D01*
X399313Y-333949D01*
X398876Y-336282D01*
X397784Y-338032D01*
X395819Y-338908D01*
X390579D01*
G01X406769Y-346199D02*
Y-328699D01*
X412446Y-343282D01*
X418123Y-328699D01*
Y-346199D01*
G01X434749Y-330158D02*
X433439Y-329282D01*
X431911Y-328699D01*
X430164D01*
X428199Y-329574D01*
X426671Y-331032D01*
X425579Y-332783D01*
X424706Y-335699D01*
X424487Y-338324D01*
X424924Y-340949D01*
X425579Y-342699D01*
X426889Y-344449D01*
X428418Y-345616D01*
X429946Y-346199D01*
X431474D01*
X433003Y-345616D01*
X434313Y-344741D01*
X435405Y-343575D01*
G01X460579Y-346199D02*
Y-328699D01*
X465819D01*
X467566Y-329574D01*
X468876Y-331616D01*
X469313Y-333949D01*
X468876Y-336282D01*
X467784Y-338032D01*
X465819Y-338908D01*
X460579D01*
G01X476987Y-328699D02*
X482446Y-346199D01*
X487905Y-328699D01*
G01X499946D02*
Y-346199D01*
G01X494924Y-328699D02*
X504968D01*
G01X284269Y-301199D02*
Y-283699D01*
X289946Y-298282D01*
X295623Y-283699D01*
Y-301199D01*
G01X307446D02*
X306136Y-300907D01*
X304826Y-299741D01*
X303952Y-297699D01*
X303516Y-295366D01*
X303952Y-293032D01*
X304826Y-290991D01*
X306136Y-289824D01*
X307446Y-289533D01*
X308756Y-289824D01*
X310066Y-290991D01*
X310939Y-293032D01*
X311158Y-295366D01*
X310939Y-297699D01*
X310066Y-299741D01*
X308756Y-300907D01*
X307446Y-301199D01*
G01X328876Y-283699D02*
Y-301199D01*
G01Y-298575D02*
X328003Y-300033D01*
X326692Y-300907D01*
X325164Y-301199D01*
X323418Y-300616D01*
X322108Y-299158D01*
X321234Y-297408D01*
X321016Y-295366D01*
X321234Y-293324D01*
X322108Y-291574D01*
X323418Y-290116D01*
X325164Y-289533D01*
X326692Y-289824D01*
X327784Y-290408D01*
X328876Y-291574D01*
G01X339171Y-293324D02*
X346158D01*
X345503Y-291282D01*
X344411Y-290116D01*
X342883Y-289533D01*
X341354Y-289824D01*
X340044Y-290699D01*
X339171Y-292741D01*
X338734Y-294491D01*
Y-296241D01*
X339171Y-297991D01*
X340263Y-299741D01*
X341573Y-300907D01*
X343101Y-301199D01*
X344629Y-300616D01*
X346158Y-298866D01*
G01X359946Y-301199D02*
Y-283699D01*
G01X556346Y-346199D02*
Y-328699D01*
X553726Y-332199D01*
G01Y-346199D02*
X558966D01*
G01X569043Y-343575D02*
X570352Y-345033D01*
X571881Y-345907D01*
X573846Y-346199D01*
X575811Y-345616D01*
X577339Y-344449D01*
X578431Y-342408D01*
X578649Y-340074D01*
X578213Y-337741D01*
X577121Y-336282D01*
X575592Y-335116D01*
X574064Y-334824D01*
X572536Y-335116D01*
X570571Y-336282D01*
X571226Y-328699D01*
X577121D01*
G01X591346Y-346199D02*
Y-328699D01*
X588726Y-332199D01*
G01Y-346199D02*
X593966D01*
G01X608846Y-328699D02*
X607099Y-329282D01*
X605789Y-330741D01*
X604916Y-332490D01*
X604261Y-334824D01*
X604043Y-337449D01*
X604261Y-340074D01*
X604916Y-342408D01*
X605789Y-344158D01*
X607099Y-345616D01*
X608846Y-346199D01*
X610592Y-345616D01*
X611903Y-344158D01*
X612776Y-342408D01*
X613431Y-340074D01*
X613649Y-337449D01*
X613431Y-334824D01*
X612776Y-332490D01*
X611903Y-330741D01*
X610592Y-329282D01*
X608846Y-328699D01*
G01X621543Y-343575D02*
X622852Y-345033D01*
X624381Y-345907D01*
X626346Y-346199D01*
X628311Y-345616D01*
X629839Y-344449D01*
X630931Y-342408D01*
X631149Y-340074D01*
X630713Y-337741D01*
X629621Y-336282D01*
X628092Y-335116D01*
X626564Y-334824D01*
X625036Y-335116D01*
X623071Y-336282D01*
X623726Y-328699D01*
X629621D01*
G01X543229Y-301199D02*
Y-283699D01*
X548469D01*
X550216Y-284574D01*
X551526Y-286616D01*
X551963Y-288949D01*
X551526Y-291282D01*
X550434Y-293032D01*
X548469Y-293908D01*
X543229D01*
G01X569899Y-285158D02*
X568589Y-284282D01*
X567061Y-283699D01*
X565314D01*
X563349Y-284574D01*
X561821Y-286032D01*
X560729Y-287783D01*
X559856Y-290699D01*
X559637Y-293324D01*
X560074Y-295949D01*
X560729Y-297699D01*
X562039Y-299449D01*
X563568Y-300616D01*
X565096Y-301199D01*
X566624D01*
X568153Y-300616D01*
X569463Y-299741D01*
X570555Y-298575D01*
G01X584342Y-291866D02*
X585216Y-290991D01*
X585871Y-289533D01*
X586308Y-287490D01*
X585871Y-285741D01*
X584998Y-284574D01*
X583469Y-283699D01*
X577574D01*
Y-301199D01*
X584779D01*
X586308Y-300033D01*
X587181Y-298282D01*
X587618Y-296241D01*
X587181Y-294199D01*
X585871Y-292449D01*
X584342Y-291866D01*
X577574D01*
G01X593546Y-307032D02*
X606646D01*
G01X612574Y-301199D02*
Y-283699D01*
X622618Y-301199D01*
Y-283699D01*
G01X635096Y-301199D02*
X633349Y-300907D01*
X631821Y-299741D01*
X630511Y-297991D01*
X629637Y-295949D01*
X629201Y-293616D01*
Y-291282D01*
X629637Y-288949D01*
X630511Y-286907D01*
X631821Y-285158D01*
X633349Y-283991D01*
X635096Y-283699D01*
X636842Y-283991D01*
X638371Y-285158D01*
X639681Y-286907D01*
X640555Y-288949D01*
X640991Y-291282D01*
Y-293616D01*
X640555Y-295949D01*
X639681Y-297991D01*
X638371Y-299741D01*
X636842Y-300907D01*
X635096Y-301199D01*
G01X685937Y-283699D02*
X691396Y-301199D01*
X696855Y-283699D01*
G01X713263Y-301199D02*
X704529D01*
Y-283699D01*
X713263D01*
G01X709769Y-292157D02*
X704529D01*
G01X722029Y-301199D02*
Y-283699D01*
X727488D01*
X729234Y-284574D01*
X730326Y-285741D01*
X730763Y-288074D01*
X730326Y-290408D01*
X729016Y-291866D01*
X727488Y-292741D01*
X722029D01*
G01X727488D02*
X730763Y-301199D01*
G01X743896Y-301782D02*
X743459Y-301491D01*
Y-300907D01*
X743896Y-300616D01*
X744333Y-300907D01*
Y-301491D01*
X743896Y-301782D01*
G01X717646Y-346199D02*
Y-328699D01*
X715026Y-332199D01*
G01Y-346199D02*
X720266D01*
G01X892100Y-336866D02*
X891226Y-335991D01*
X890571Y-334533D01*
X890134Y-332490D01*
X890571Y-330741D01*
X891444Y-329574D01*
X892973Y-328699D01*
X898868D01*
Y-346199D01*
X891663D01*
X890134Y-345033D01*
X889261Y-343282D01*
X888824Y-341241D01*
X889261Y-339199D01*
X890571Y-337449D01*
X892100Y-336866D01*
X898868D01*
G01X882023Y-346199D02*
Y-328699D01*
X876346Y-343282D01*
X870669Y-328699D01*
Y-346199D01*
G01X864305D02*
X858846Y-328699D01*
X853387Y-346199D01*
G01X855353Y-340074D02*
X862340D01*
G01X845931Y-343866D02*
X844184Y-345324D01*
X842219Y-346199D01*
X840473D01*
X838726Y-345324D01*
X837416Y-343866D01*
X836761Y-341824D01*
X837198Y-339783D01*
X838289Y-338032D01*
X840254Y-336866D01*
X842874Y-336282D01*
X844403Y-335116D01*
X845058Y-333074D01*
X844621Y-331032D01*
X843529Y-329574D01*
X842001Y-328699D01*
X840473D01*
X838944Y-329282D01*
X837634Y-330741D01*
G01X828649Y-346199D02*
Y-328699D01*
G01X820353D02*
X828649Y-339491D01*
G01X819043Y-346199D02*
X824938Y-334533D01*
G01X819479Y-283699D02*
Y-301199D01*
X828213D01*
G01X845276D02*
Y-289533D01*
G01Y-291574D02*
X844403Y-290408D01*
X843092Y-289824D01*
X841564Y-289533D01*
X840036Y-290116D01*
X838726Y-291282D01*
X837852Y-293032D01*
X837416Y-295366D01*
X837852Y-297699D01*
X838726Y-299449D01*
X840036Y-300616D01*
X841564Y-301199D01*
X843092Y-300907D01*
X844403Y-300033D01*
X845276Y-298866D01*
G01X854261Y-306449D02*
X855571Y-307032D01*
X857318Y-306449D01*
X858409Y-305283D01*
X859283Y-303824D01*
X860592Y-299158D01*
X863431Y-289533D01*
G01X856444D02*
X860592Y-299158D01*
G01X873071Y-293324D02*
X880058D01*
X879403Y-291282D01*
X878311Y-290116D01*
X876783Y-289533D01*
X875254Y-289824D01*
X873944Y-290699D01*
X873071Y-292741D01*
X872634Y-294491D01*
Y-296241D01*
X873071Y-297991D01*
X874163Y-299741D01*
X875473Y-300907D01*
X877001Y-301199D01*
X878529Y-300616D01*
X880058Y-298866D01*
G01X890789Y-301199D02*
Y-289533D01*
G01Y-291866D02*
X891881Y-290699D01*
X892973Y-289824D01*
X894501Y-289533D01*
X895592Y-289824D01*
X896903Y-290699D01*
G01X959846Y-328699D02*
X962902Y-346199D01*
X966396Y-328699D01*
X969889Y-346199D01*
X972946Y-328699D01*
G01X979529Y-346199D02*
Y-328699D01*
X984769D01*
X986516Y-329574D01*
X987826Y-331616D01*
X988263Y-333949D01*
X987826Y-336282D01*
X986734Y-338032D01*
X984769Y-338908D01*
X979529D01*
G01X996811Y-346199D02*
Y-328699D01*
G01X1005981D02*
Y-346199D01*
G01Y-337449D02*
X996811D01*
G01X1016058Y-340366D02*
X1021734D01*
G01X1031593Y-346199D02*
Y-328699D01*
G01X1039889D02*
X1031593Y-339491D01*
G01X1041199Y-346199D02*
X1035304Y-334533D01*
G01X1058263Y-346199D02*
X1049529D01*
Y-328699D01*
X1058263D01*
G01X1054769Y-337157D02*
X1049529D01*
G01X1066374Y-346199D02*
Y-328699D01*
X1076418Y-346199D01*
Y-328699D01*
G01X1083874Y-346199D02*
Y-328699D01*
X1093918Y-346199D01*
Y-328699D01*
G01X961593Y-301199D02*
Y-283699D01*
X965959D01*
X967706Y-284574D01*
X969016Y-285741D01*
X970108Y-287490D01*
X970981Y-289533D01*
X971199Y-292449D01*
X970981Y-295366D01*
X970108Y-297408D01*
X969016Y-299158D01*
X967706Y-300324D01*
X965959Y-301199D01*
X961593D01*
G01X980621Y-293324D02*
X987608D01*
X986953Y-291282D01*
X985861Y-290116D01*
X984333Y-289533D01*
X982804Y-289824D01*
X981494Y-290699D01*
X980621Y-292741D01*
X980184Y-294491D01*
Y-296241D01*
X980621Y-297991D01*
X981713Y-299741D01*
X983023Y-300907D01*
X984551Y-301199D01*
X986079Y-300616D01*
X987608Y-298866D01*
G01X998121Y-299158D02*
X999213Y-300324D01*
X1000741Y-301199D01*
X1002051D01*
X1003361Y-300616D01*
X1004234Y-299741D01*
X1004671Y-298575D01*
X1004453Y-296824D01*
X1003579Y-295949D01*
X999649Y-294199D01*
X998776Y-292157D01*
X999213Y-290699D01*
X1000086Y-289824D01*
X1001396Y-289533D01*
X1002706Y-289824D01*
X1004016Y-290699D01*
G01X1018896Y-289533D02*
Y-301199D01*
G01Y-284866D02*
X1018459Y-284574D01*
Y-283991D01*
X1018896Y-283699D01*
X1019333Y-283991D01*
Y-284574D01*
X1018896Y-284866D01*
G01X1033339Y-305574D02*
X1034868Y-306741D01*
X1036614Y-307032D01*
X1038142Y-306741D01*
X1039453Y-305283D01*
X1040326Y-303241D01*
Y-289533D01*
G01Y-291866D02*
X1039453Y-290699D01*
X1038142Y-289824D01*
X1036614Y-289533D01*
X1034868Y-290116D01*
X1033776Y-291282D01*
X1032902Y-293324D01*
X1032466Y-295366D01*
X1032684Y-297116D01*
X1033558Y-299158D01*
X1034868Y-300616D01*
X1036614Y-301199D01*
X1037924Y-300907D01*
X1039453Y-299741D01*
X1040326Y-298575D01*
G01X1050184Y-301199D02*
Y-289533D01*
G01Y-292449D02*
X1051058Y-290991D01*
X1052368Y-289824D01*
X1054114Y-289533D01*
X1055642Y-289824D01*
X1056953Y-290991D01*
X1057608Y-293032D01*
Y-301199D01*
G01X1068121Y-293324D02*
X1075108D01*
X1074453Y-291282D01*
X1073361Y-290116D01*
X1071833Y-289533D01*
X1070304Y-289824D01*
X1068994Y-290699D01*
X1068121Y-292741D01*
X1067684Y-294491D01*
Y-296241D01*
X1068121Y-297991D01*
X1069213Y-299741D01*
X1070523Y-300907D01*
X1072051Y-301199D01*
X1073579Y-300616D01*
X1075108Y-298866D01*
G01X1085839Y-301199D02*
Y-289533D01*
G01Y-291866D02*
X1086931Y-290699D01*
X1088023Y-289824D01*
X1089551Y-289533D01*
X1090642Y-289824D01*
X1091953Y-290699D01*
G01X1132596Y-346199D02*
Y-328699D01*
X1129976Y-332199D01*
G01Y-346199D02*
X1135216D01*
G01X1150096D02*
Y-328699D01*
X1147476Y-332199D01*
G01Y-346199D02*
X1152716D01*
G01X1163666Y-346782D02*
X1171526Y-328699D01*
G01X1185096Y-346199D02*
Y-328699D01*
X1182476Y-332199D01*
G01Y-346199D02*
X1187716D01*
G01X1198448Y-338908D02*
X1199976Y-336866D01*
X1201286Y-335699D01*
X1203033Y-335116D01*
X1204561Y-335699D01*
X1205653Y-336866D01*
X1206526Y-338616D01*
X1206744Y-340657D01*
X1206526Y-342408D01*
X1205653Y-344158D01*
X1204342Y-345616D01*
X1202814Y-346199D01*
X1201068Y-345616D01*
X1199539Y-343866D01*
X1198666Y-341241D01*
X1198448Y-338324D01*
X1198884Y-334533D01*
X1199539Y-332490D01*
X1200631Y-330449D01*
X1202159Y-328991D01*
X1203688Y-328699D01*
X1205216Y-329282D01*
X1206308Y-330741D01*
G01X1216166Y-346782D02*
X1224026Y-328699D01*
G01X1233448Y-331616D02*
X1234758Y-329866D01*
X1236286Y-328991D01*
X1238033Y-328699D01*
X1240216Y-329282D01*
X1241744Y-330741D01*
X1242181Y-332490D01*
X1241963Y-334241D01*
X1241089Y-335699D01*
X1236723Y-338616D01*
X1234758Y-340657D01*
X1233448Y-343575D01*
X1233011Y-346199D01*
X1242181D01*
G01X1255096Y-328699D02*
X1253349Y-329282D01*
X1252039Y-330741D01*
X1251166Y-332490D01*
X1250511Y-334824D01*
X1250293Y-337449D01*
X1250511Y-340074D01*
X1251166Y-342408D01*
X1252039Y-344158D01*
X1253349Y-345616D01*
X1255096Y-346199D01*
X1256842Y-345616D01*
X1258153Y-344158D01*
X1259026Y-342408D01*
X1259681Y-340074D01*
X1259899Y-337449D01*
X1259681Y-334824D01*
X1259026Y-332490D01*
X1258153Y-330741D01*
X1256842Y-329282D01*
X1255096Y-328699D01*
G01X1272596Y-346199D02*
Y-328699D01*
X1269976Y-332199D01*
G01Y-346199D02*
X1275216D01*
G01X1285948Y-338908D02*
X1287476Y-336866D01*
X1288786Y-335699D01*
X1290533Y-335116D01*
X1292061Y-335699D01*
X1293153Y-336866D01*
X1294026Y-338616D01*
X1294244Y-340657D01*
X1294026Y-342408D01*
X1293153Y-344158D01*
X1291842Y-345616D01*
X1290314Y-346199D01*
X1288568Y-345616D01*
X1287039Y-343866D01*
X1286166Y-341241D01*
X1285948Y-338324D01*
X1286384Y-334533D01*
X1287039Y-332490D01*
X1288131Y-330449D01*
X1289659Y-328991D01*
X1291188Y-328699D01*
X1292716Y-329282D01*
X1293808Y-330741D01*
G01X1180293Y-301199D02*
Y-283699D01*
X1184659D01*
X1186406Y-284574D01*
X1187716Y-285741D01*
X1188808Y-287490D01*
X1189681Y-289533D01*
X1189899Y-292449D01*
X1189681Y-295366D01*
X1188808Y-297408D01*
X1187716Y-299158D01*
X1186406Y-300324D01*
X1184659Y-301199D01*
X1180293D01*
G01X1206526D02*
Y-289533D01*
G01Y-291574D02*
X1205653Y-290408D01*
X1204342Y-289824D01*
X1202814Y-289533D01*
X1201286Y-290116D01*
X1199976Y-291282D01*
X1199102Y-293032D01*
X1198666Y-295366D01*
X1199102Y-297699D01*
X1199976Y-299449D01*
X1201286Y-300616D01*
X1202814Y-301199D01*
X1204342Y-300907D01*
X1205653Y-300033D01*
X1206526Y-298866D01*
G01X1220096Y-283699D02*
Y-301199D01*
G01X1217039Y-289533D02*
X1223153D01*
G01X1234321Y-293324D02*
X1241308D01*
X1240653Y-291282D01*
X1239561Y-290116D01*
X1238033Y-289533D01*
X1236504Y-289824D01*
X1235194Y-290699D01*
X1234321Y-292741D01*
X1233884Y-294491D01*
Y-296241D01*
X1234321Y-297991D01*
X1235413Y-299741D01*
X1236723Y-300907D01*
X1238251Y-301199D01*
X1239779Y-300616D01*
X1241308Y-298866D01*
G54D43*
X165800Y512500D03*
Y509000D03*
Y505500D03*
X165819Y521720D03*
X165800Y516000D03*
X185300Y443300D03*
X615863Y253108D03*
X643300Y355600D03*
Y359600D03*
X877948Y764898D03*
X1009012Y35919D03*
G54D34*
X122165Y142874D03*
X173897D03*
G54D52*
X476614Y167493D03*
Y162493D03*
Y157493D03*
G54D16*
X4100Y865800D03*
X46678Y-681D03*
X50400Y826100D03*
X107400Y119000D03*
X1374900Y761800D03*
X1383700Y138500D03*
X1396600Y862800D03*
G54D61*
X900668Y161468D03*
X902868D03*
X905000Y165300D03*
X907200D03*
X899000Y169268D03*
X901200D03*
X899000Y173218D03*
X901200D03*
X899000Y196818D03*
X901200D03*
X899000Y208668D03*
X901200D03*
X899000Y200768D03*
X901200D03*
X899000Y204718D03*
X901200D03*
X899000Y192918D03*
X901200D03*
X899000Y188968D03*
X901200D03*
X904100Y185200D03*
X906300D03*
X899000Y181068D03*
X901200D03*
X899000Y177168D03*
X901200D03*
X899000Y236200D03*
X901200D03*
X899000Y212568D03*
X901200D03*
X899000Y216518D03*
X901200D03*
X899000Y220468D03*
X901200D03*
X899000Y224368D03*
X901200D03*
X899000Y228318D03*
X901200D03*
X899000Y232268D03*
X901200D03*
X938200Y141700D03*
X940400D03*
X930250Y157500D03*
X932450D03*
X938350D03*
X940550D03*
X932600Y165338D03*
X934800D03*
X940500D03*
X924500Y173218D03*
X926700D03*
X932600D03*
X934800D03*
X940500D03*
X932600Y185168D03*
X934800D03*
X940500D03*
X924500Y192900D03*
X926700D03*
X940500D03*
X932600D03*
X934800D03*
X918300Y216550D03*
X920500D03*
X934400Y232300D03*
X936600D03*
X926400D03*
X928600D03*
X934400Y224400D03*
X936600D03*
X926400D03*
X928600D03*
X940500Y212600D03*
X957400Y126000D03*
X959600D03*
X964050Y161400D03*
X966250D03*
X970900Y149600D03*
X973100D03*
X942700Y165338D03*
Y173218D03*
X956100Y185168D03*
X958300D03*
X948100Y204700D03*
X950300D03*
X948100Y185168D03*
X950300D03*
X956100Y204700D03*
X958300D03*
X964000D03*
X966200D03*
X971800D03*
X974000D03*
X942700Y185168D03*
Y192900D03*
X948100D03*
X950300D03*
X950100Y236210D03*
X952300D03*
X965700Y220500D03*
X967900D03*
X957900Y228327D03*
X960100D03*
X957800Y220500D03*
X960000D03*
X957900Y236210D03*
X960100D03*
X965800Y236200D03*
X968000D03*
X950100Y220500D03*
X952300D03*
X965800Y228300D03*
X968000D03*
X950100Y228327D03*
X952300D03*
X948100Y212600D03*
X950300D03*
X956100D03*
X958300D03*
X964000D03*
X966200D03*
X971600Y212624D03*
X973800D03*
X942700Y212600D03*
X997300Y137768D03*
X999500D03*
X997300Y129900D03*
X999500D03*
X997300Y141768D03*
X999500D03*
X982500Y137800D03*
X984700D03*
X997300Y145668D03*
X999500D03*
X997300Y149618D03*
X999500D03*
X997300Y153600D03*
X999500D03*
X999168Y161468D03*
X1001368D03*
X981500Y177150D03*
X983700D03*
X981350Y185050D03*
X983550D03*
X1001100Y236200D03*
X1003300D03*
X981400Y216505D03*
X983600D03*
G54D25*
X67400Y269300D03*
X72100D03*
X228500Y156200D03*
X276200Y154100D03*
G54D26*
X67400Y274900D03*
X72100D03*
X228500Y161800D03*
X276200Y159700D03*
G54D17*
X42587Y151614D03*
X80579D03*
G54D53*
X473231Y235560D03*
Y274930D03*
X487404Y255245D03*
G54D44*
X193900Y274372D03*
X183900D03*
X213900D03*
X203900D03*
X302500Y207200D03*
X292500D03*
X326200D03*
X336200D03*
X312500D03*
X346200D03*
X465485Y200680D03*
Y190680D03*
Y180680D03*
X488462Y180761D03*
Y190761D03*
Y200761D03*
X501742Y215594D03*
X511742D03*
X521742D03*
X531742D03*
X772300Y16200D03*
X762300D03*
X752300D03*
X785300Y16100D03*
X795300D03*
X805300D03*
X819291Y265354D03*
Y285354D03*
X1075197Y92126D03*
Y112126D03*
X1348785Y161642D03*
X1323195D03*
X1348785Y179358D03*
X1323195D03*
G54D35*
X134251Y153543D03*
X161811D03*
X151968D03*
X144094D03*
G54D62*
X943111Y5908D03*
X935236D03*
X927361D03*
X919486D03*
X911616D03*
X943111Y13778D03*
X935236D03*
X927361D03*
X919486D03*
X911616D03*
X958856Y5908D03*
X950986D03*
X958856Y13778D03*
X950986D03*
G54D36*
X105500Y287800D03*
X103500Y457800D03*
X113000Y458800D03*
X197800Y443800D03*
X189600Y443700D03*
X193600D03*
X185500Y457800D03*
X197700Y454635D03*
X177500Y457800D03*
X184500Y545300D03*
X232600Y98600D03*
X210086Y201400D03*
X206076D03*
X202638Y434145D03*
X220838Y431945D03*
X201800Y443800D03*
X230572Y458913D03*
X201700Y454635D03*
X210300Y454100D03*
X214300D03*
X225000Y534800D03*
Y518300D03*
X249995Y98758D03*
X236800Y98500D03*
X251000Y498200D03*
X263000Y752300D03*
X290500Y145800D03*
X285000Y748800D03*
X267500D03*
X295678Y732731D03*
X278050Y733317D03*
X298554Y719713D03*
X286406Y719698D03*
X282406D03*
X290500Y719800D03*
X294506Y719698D03*
X293678Y756731D03*
X289678D03*
X279500Y756300D03*
X282378Y768731D03*
X301000Y744300D03*
X317000Y744800D03*
X311678Y732731D03*
X327678D03*
X310406Y719698D03*
X302554Y719713D03*
X311178Y756731D03*
X307178D03*
X325678D03*
X321678D03*
X495906Y771698D03*
X499906D03*
X498000Y800800D03*
X480800D03*
X502678Y808731D03*
X492500Y808300D03*
X482000D03*
X491900Y784700D03*
X495878Y820731D03*
X521820Y130370D03*
X513820D03*
X525820D03*
X517820D03*
X527000Y771500D03*
X521900Y771400D03*
X517800Y771500D03*
X513700D03*
X509600D03*
X514000Y795800D03*
X530000D03*
X506678Y808731D03*
X520178D03*
X524678Y784731D03*
X534678Y808731D03*
X524178D03*
X570345Y130330D03*
X538678Y808731D03*
X540678Y784731D03*
X542800Y809100D03*
X578467Y130330D03*
X582467D03*
X574345D03*
X584363Y220908D03*
X592363D03*
X588363D03*
X620048Y130544D03*
X612026Y130552D03*
X624048Y130544D03*
X616026Y130552D03*
X659500Y130300D03*
X650500D03*
X655000D03*
X646000D03*
X641963Y234908D03*
X720100Y38100D03*
X715390Y29680D03*
X715130Y53200D03*
X834252Y14300D03*
X820212Y14219D03*
X830252Y14300D03*
X826138Y13604D03*
X838252Y14300D03*
X846252D03*
X873100Y27300D03*
X842252Y14300D03*
X864906Y748698D03*
X868906D03*
X857500Y778300D03*
X841000Y774800D03*
X852400Y762200D03*
X870400Y785700D03*
X844810Y785890D03*
X865378Y797731D03*
X877300Y27300D03*
X906500Y78800D03*
X902000D03*
X897500D03*
X893000D03*
X888500D03*
X875000D03*
X884000D03*
X879500D03*
X893406Y748698D03*
X889306D03*
X885306D03*
X881306D03*
X877200Y748600D03*
X887500Y781300D03*
X882203Y762295D03*
X878600Y785300D03*
X896178Y785731D03*
X892178D03*
X911000Y78800D03*
X915500D03*
X920000D03*
X933500D03*
X929000D03*
X924500D03*
X938000D03*
X951500D03*
Y89800D03*
X947000Y78800D03*
Y89800D03*
X942500Y78800D03*
Y89800D03*
X956000Y78800D03*
X994700Y101100D03*
X1069700Y4600D03*
X1044161Y17868D03*
X1068750Y24550D03*
X1073250Y36550D03*
X1065475Y40873D03*
X1061342Y64994D03*
X1310128Y677167D03*
X1302000Y703300D03*
X1298000Y707300D03*
X1312900Y690200D03*
X1310900Y713700D03*
X1310100Y726200D03*
X1338128Y677167D03*
X1330128D03*
X1326128D03*
X1322128D03*
X1314128D03*
X1319500Y705800D03*
X1336000Y701800D03*
X1329900Y714200D03*
X1325900D03*
X1330400Y690200D03*
X1344900Y714200D03*
X1340900D03*
X1346900Y690200D03*
G54D27*
X92200Y273940D03*
X95959Y513567D03*
X82017Y490086D03*
Y494086D03*
X84200Y510500D03*
Y502500D03*
X95387Y496084D03*
Y500084D03*
X84200Y506500D03*
X95387Y504084D03*
X84200Y514500D03*
X95820Y541681D03*
X96736Y526266D03*
X95959Y517567D03*
X84200Y518500D03*
X95820Y545681D03*
X70700Y535000D03*
X84200Y538500D03*
Y534500D03*
X70300Y526900D03*
X74200Y522500D03*
X96736Y530266D03*
X74000Y545700D03*
X84200Y554500D03*
X95820Y549681D03*
X84162Y558640D03*
X101900Y275460D03*
X130592Y470680D03*
X135109Y426337D03*
X135108Y430365D03*
X181700Y517500D03*
X214338Y441845D03*
X211238Y425445D03*
X217800Y448200D03*
X204600Y502800D03*
Y506800D03*
Y510900D03*
Y514900D03*
X213200Y542500D03*
Y538500D03*
Y546500D03*
Y550500D03*
X254200Y477500D03*
X243600Y455600D03*
Y473600D03*
X234843Y477829D03*
Y473829D03*
X254200Y481500D03*
X253200Y486000D03*
Y490000D03*
X234843Y485929D03*
Y489929D03*
X234800Y506000D03*
Y502000D03*
X718750Y17920D03*
X870100Y765800D03*
X858640Y790220D03*
X905600Y112500D03*
X900000Y765400D03*
X1007628Y23605D03*
Y27605D03*
X1037681Y2842D03*
X1045263Y2948D03*
X1052112Y18357D03*
X1073200Y36500D03*
X1068700Y24500D03*
X1073200Y32500D03*
X1068700Y20500D03*
X1054900Y36615D03*
X1065425Y48823D03*
Y44323D03*
X1061346Y68390D03*
Y72400D03*
X1077500Y3500D03*
X1077600Y12400D03*
X1077500Y7600D03*
X1378239Y169235D03*
G54D45*
X195000Y409040D03*
Y411600D03*
X187600Y409040D03*
Y411600D03*
X195000Y414160D03*
X187600D03*
X207938Y436405D03*
Y433845D03*
Y431285D03*
X215338Y436405D03*
Y433845D03*
Y431285D03*
G54D54*
X514309Y-315D03*
Y52087D03*
X530057Y106457D03*
X557616Y-315D03*
Y52087D03*
X547773Y106457D03*
X600923Y-315D03*
Y52087D03*
X591080Y106457D03*
X573364D03*
X634388D03*
X616671D03*
X644230Y-315D03*
Y52087D03*
X659978Y106457D03*
X687537Y-315D03*
Y52087D03*
X677695Y106457D03*
X1116671Y-315D03*
Y52087D03*
X1132419Y106457D03*
X1159978Y-315D03*
Y52087D03*
X1175726Y106457D03*
X1150135D03*
X1203285Y-315D03*
Y52087D03*
X1193442Y106457D03*
X1246592Y-315D03*
Y52087D03*
X1236750Y106457D03*
X1219033D03*
X1280057D03*
X1262340D03*
X1289899Y-315D03*
Y52087D03*
G54D18*
X41603Y177598D03*
X65579D03*
X57587D03*
X49595D03*
X45559Y187598D03*
X37567D03*
X53551D03*
X73571Y177598D03*
X81563D03*
X77607Y187598D03*
X69615D03*
X85599D03*
G54D63*
X907900Y127000D03*
Y124800D03*
X915793Y127000D03*
Y124800D03*
X923600Y127000D03*
Y124800D03*
X931532Y127000D03*
Y124800D03*
X915768Y180068D03*
Y177868D03*
X915730Y237800D03*
Y235600D03*
X919700Y237800D03*
Y235600D03*
X907893Y237800D03*
Y235600D03*
X911800Y237800D03*
Y235600D03*
X923604Y237900D03*
Y235700D03*
X966900Y127100D03*
Y124900D03*
X974768Y127100D03*
Y124900D03*
X970845Y237600D03*
Y235400D03*
X974800Y237600D03*
Y235400D03*
X982728Y127100D03*
Y124900D03*
X978760Y237600D03*
Y235400D03*
X982697Y237600D03*
Y235400D03*
X986600Y237600D03*
Y235400D03*
G54D28*
X88800Y273940D03*
X92559Y513567D03*
X78617Y490086D03*
Y494086D03*
X80800Y510500D03*
Y502500D03*
X91987Y496084D03*
Y500084D03*
X80800Y506500D03*
X91987Y504084D03*
X80800Y514500D03*
X92420Y541681D03*
X93336Y526266D03*
X92559Y517567D03*
X80800Y518500D03*
X92420Y545681D03*
X67300Y535000D03*
X80800Y538500D03*
Y534500D03*
X66900Y526900D03*
X70800Y522500D03*
X93336Y530266D03*
X70600Y545700D03*
X80800Y554500D03*
X92420Y549681D03*
X80762Y558640D03*
X98500Y275460D03*
X131709Y426337D03*
X131708Y430365D03*
X127192Y470680D03*
X178300Y517500D03*
X210938Y441845D03*
X207838Y425445D03*
X231443Y477829D03*
X214400Y448200D03*
X231443Y473829D03*
X201200Y502800D03*
Y506800D03*
X231443Y485929D03*
Y489929D03*
X231400Y506000D03*
Y502000D03*
X201200Y510900D03*
Y514900D03*
X209800Y542500D03*
Y538500D03*
Y546500D03*
Y550500D03*
X250800Y477500D03*
X240200Y455600D03*
Y473600D03*
X250800Y481500D03*
X249800Y486000D03*
Y490000D03*
X715350Y17920D03*
X866700Y765800D03*
X855240Y790220D03*
X902200Y112500D03*
X896600Y765400D03*
X1004228Y23605D03*
Y27605D03*
X1041863Y2948D03*
X1034281Y2842D03*
X1074100Y3500D03*
X1074200Y12400D03*
X1074100Y7600D03*
X1048712Y18357D03*
X1069800Y36500D03*
X1065300Y24500D03*
X1069800Y32500D03*
X1065300Y20500D03*
X1051500Y36615D03*
X1062025Y48823D03*
Y44323D03*
X1057946Y68390D03*
Y72400D03*
X1374839Y169235D03*
G54D19*
X54378Y237402D03*
G54D64*
X927600Y142700D03*
Y144900D03*
X939400Y144500D03*
Y146700D03*
X931500Y144600D03*
Y146800D03*
X951200Y144800D03*
Y147000D03*
X943400Y144700D03*
Y146900D03*
X946400Y159200D03*
Y161400D03*
G54D46*
X240840Y460900D03*
X243400D03*
X245960D03*
X240840Y468300D03*
X243400D03*
X245960D03*
G54D55*
X535962Y37484D03*
X579269D03*
X622577D03*
X665884D03*
X1138324D03*
X1181631D03*
X1224939D03*
X1268246D03*
G54D37*
X105500Y291200D03*
X103500Y461200D03*
X113000Y462200D03*
X185500Y461200D03*
X197800Y447200D03*
X189600Y447100D03*
X193600D03*
X197700Y458035D03*
X177500Y461200D03*
X184500Y548700D03*
X232600Y102000D03*
X210086Y204800D03*
X206076D03*
X202638Y437545D03*
X220838Y435345D03*
X230572Y462313D03*
X201800Y447200D03*
X201700Y458035D03*
X210300Y457500D03*
X214300D03*
X225000Y538200D03*
Y521700D03*
X249995Y102158D03*
X236800Y101900D03*
X251000Y501600D03*
X263000Y755700D03*
X290500Y149200D03*
X295678Y736131D03*
X278050Y736717D03*
X298554Y723113D03*
X286406Y723098D03*
X282406D03*
X290500Y723200D03*
X294506Y723098D03*
X285000Y752200D03*
X267500D03*
X293678Y760131D03*
X289678D03*
X279500Y759700D03*
X282378Y772131D03*
X301000Y747700D03*
X317000Y748200D03*
X311678Y736131D03*
X327678D03*
X310406Y723098D03*
X302554Y723113D03*
X311178Y760131D03*
X307178D03*
X325678D03*
X321678D03*
X495906Y775098D03*
X499906D03*
X498000Y804200D03*
X480800D03*
X502678Y812131D03*
X492500Y811700D03*
X482000D03*
X491900Y788100D03*
X495878Y824131D03*
X521820Y133770D03*
X513820D03*
X525820D03*
X517820D03*
X527000Y774900D03*
X521900Y774800D03*
X517800Y774900D03*
X513700D03*
X509600D03*
X514000Y799200D03*
X530000D03*
X506678Y812131D03*
X520178D03*
X524678Y788131D03*
X534678Y812131D03*
X524178D03*
X570345Y133730D03*
X538678Y812131D03*
X540678Y788131D03*
X542800Y812500D03*
X578467Y133730D03*
X582467D03*
X574345D03*
X584363Y224308D03*
X592363D03*
X588363D03*
X620048Y133944D03*
X612026Y133952D03*
X624048Y133944D03*
X616026Y133952D03*
X659500Y133700D03*
X650500D03*
X655000D03*
X646000D03*
X641963Y238308D03*
X715390Y33080D03*
X720100Y41500D03*
X715130Y56600D03*
X834252Y17700D03*
X820212Y17619D03*
X830252Y17700D03*
X826138Y17004D03*
X838252Y17700D03*
X846252D03*
X873100Y30700D03*
X842252Y17700D03*
X857500Y781700D03*
X841000Y778200D03*
X852400Y765600D03*
X864906Y752098D03*
X868906D03*
X870400Y789100D03*
X844810Y789290D03*
X865378Y801131D03*
X877300Y30700D03*
X906500Y82200D03*
X902000D03*
X897500D03*
X893000D03*
X888500D03*
X875000D03*
X884000D03*
X879500D03*
X882203Y765695D03*
X893406Y752098D03*
X889306D03*
X885306D03*
X881306D03*
X877200Y752000D03*
X887500Y784700D03*
X878600Y788700D03*
X896178Y789131D03*
X892178D03*
X911000Y82200D03*
X915500D03*
X920000D03*
X933500D03*
X929000D03*
X924500D03*
X938000D03*
X951500D03*
Y93200D03*
X947000Y82200D03*
Y93200D03*
X942500Y82200D03*
Y93200D03*
X956000Y82200D03*
X994700Y104500D03*
X1069700Y8000D03*
X1044161Y21268D03*
X1068750Y27950D03*
X1073250Y39950D03*
X1061342Y68394D03*
X1065475Y44273D03*
X1310128Y680567D03*
X1302000Y706700D03*
X1298000Y710700D03*
X1312900Y693600D03*
X1310900Y717100D03*
X1310100Y729600D03*
X1338128Y680567D03*
X1330128D03*
X1326128D03*
X1322128D03*
X1314128D03*
X1319500Y709200D03*
X1336000Y705200D03*
X1330400Y693600D03*
X1329900Y717600D03*
X1325900D03*
X1344900D03*
X1340900D03*
X1346900Y693600D03*
G54D38*
X120351Y630236D03*
X126851D03*
X143217Y501760D03*
X156862Y501811D03*
X152916Y501536D03*
X146960Y501630D03*
X165851Y627736D03*
X137551Y625736D03*
X149851Y627736D03*
X155851D03*
X160851D03*
X217000Y538300D03*
X221000Y529300D03*
X500332Y133764D03*
X493245Y133625D03*
X489680Y133605D03*
X503827Y133704D03*
X563002Y137395D03*
X559591D03*
X597044Y133868D03*
X593636D03*
X600522Y133853D03*
X603924D03*
X635500Y349900D03*
X630500D03*
X627000D03*
X639000D03*
X848660Y789290D03*
X1175156Y138119D03*
X1171622Y139828D03*
X1168207Y139826D03*
X1178558Y138118D03*
X1240709Y150353D03*
X1237308D03*
X1269834Y147434D03*
X1266432D03*
X1289500Y277800D03*
G54D47*
X280300Y148900D03*
X301700Y780100D03*
X573634Y243270D03*
X621263Y233108D03*
X695200Y817300D03*
X716287Y201942D03*
X1162807Y823010D03*
X1306700Y271400D03*
X1323900Y817400D03*
G54D56*
X533010Y69803D03*
X530057Y67048D03*
X535962Y64292D03*
X524151Y69803D03*
X527104Y64292D03*
X535962Y49331D03*
X527104D03*
X530057Y52087D03*
X533010Y54843D03*
X524151D03*
X533010Y99725D03*
X530057Y96969D03*
X535962Y94213D03*
X524151Y99725D03*
X527104Y94213D03*
X533010Y84764D03*
X530057Y82008D03*
X535962Y79252D03*
X524151Y84764D03*
X527104Y79252D03*
X567458Y54843D03*
X570411Y49331D03*
Y64292D03*
X567458Y69803D03*
X541868D03*
X538915Y67048D03*
X547773D03*
X544821Y64292D03*
Y49331D03*
X547773Y52087D03*
X538915D03*
X541868Y54843D03*
X570411Y79252D03*
Y94213D03*
X567458Y84764D03*
Y99725D03*
X541868D03*
X538915Y96969D03*
X547773D03*
X544821Y94213D03*
X541868Y84764D03*
X538915Y82008D03*
X547773D03*
X544821Y79252D03*
X576317Y54843D03*
X585175D03*
X573364Y52087D03*
X582222D03*
X591080D03*
X579269Y49331D03*
X588128D03*
X576317Y69803D03*
X585175D03*
X573364Y67048D03*
X582222D03*
X591080D03*
X579269Y64292D03*
X588128D03*
X579269Y79252D03*
X588128D03*
X582222Y82008D03*
X591080D03*
X585175Y84764D03*
X576317D03*
X573364Y82008D03*
X576317Y99725D03*
X585175D03*
X573364Y96969D03*
X582222D03*
X579269Y94213D03*
X588128D03*
X591080Y96969D03*
X619624Y54843D03*
X628482D03*
X616671Y52087D03*
X625529D03*
X634388D03*
X622577Y49331D03*
X631435D03*
X619624Y69803D03*
X628482D03*
X616671Y67048D03*
X625529D03*
X634388D03*
X622577Y64292D03*
X631435D03*
X610766Y54843D03*
X613718Y49331D03*
Y64292D03*
X610766Y69803D03*
X622577Y79252D03*
X631435D03*
X625529Y82008D03*
X634388D03*
X628482Y84764D03*
X619624D03*
X616671Y82008D03*
X619624Y99725D03*
X628482D03*
X616671Y96969D03*
X625529D03*
X622577Y94213D03*
X631435D03*
X634388Y96969D03*
X613718Y79252D03*
Y94213D03*
X610766Y84764D03*
Y99725D03*
X662931Y54843D03*
X671789D03*
X659978Y52087D03*
X668836D03*
X665884Y49331D03*
X662931Y69803D03*
X671789D03*
X659978Y67048D03*
X668836D03*
X665884Y64292D03*
X654073Y54843D03*
X657025Y49331D03*
Y64292D03*
X654073Y69803D03*
X665884Y79252D03*
X668836Y82008D03*
X671789Y84764D03*
X662931D03*
X659978Y82008D03*
X662931Y99725D03*
X671789D03*
X659978Y96969D03*
X668836D03*
X665884Y94213D03*
X657025Y79252D03*
Y94213D03*
X654073Y84764D03*
Y99725D03*
X677695Y52087D03*
X674742Y49331D03*
X677695Y67048D03*
X674742Y64292D03*
Y79252D03*
X677695Y82008D03*
X674742Y94213D03*
X677695Y96969D03*
X1135372Y69803D03*
X1144230D03*
X1132419Y67048D03*
X1141277D03*
X1138324Y64292D03*
X1126513Y69803D03*
X1129466Y64292D03*
X1138324Y49331D03*
X1129466D03*
X1141277Y52087D03*
X1132419D03*
X1144230Y54843D03*
X1135372D03*
X1126513D03*
X1135372Y99725D03*
X1144230D03*
X1132419Y96969D03*
X1141277D03*
X1138324Y94213D03*
X1126513Y99725D03*
X1129466Y94213D03*
X1135372Y84764D03*
X1144230D03*
X1132419Y82008D03*
X1141277D03*
X1138324Y79252D03*
X1126513Y84764D03*
X1129466Y79252D03*
X1178679Y54843D03*
X1175726Y52087D03*
X1178679Y69803D03*
X1175726Y67048D03*
X1169820Y54843D03*
X1172773Y49331D03*
Y64292D03*
X1169820Y69803D03*
X1150135Y67048D03*
X1147183Y64292D03*
Y49331D03*
X1150135Y52087D03*
X1178679Y84764D03*
X1175726Y82008D03*
X1178679Y99725D03*
X1175726Y96969D03*
X1172773Y79252D03*
Y94213D03*
X1169820Y84764D03*
Y99725D03*
X1150135Y96969D03*
X1147183Y94213D03*
X1150135Y82008D03*
X1147183Y79252D03*
X1187537Y54843D03*
X1184584Y52087D03*
X1193442D03*
X1181631Y49331D03*
X1190490D03*
X1187537Y69803D03*
X1184584Y67048D03*
X1193442D03*
X1181631Y64292D03*
X1190490D03*
X1181631Y79252D03*
X1190490D03*
X1184584Y82008D03*
X1193442D03*
X1187537Y84764D03*
Y99725D03*
X1184584Y96969D03*
X1181631Y94213D03*
X1190490D03*
X1193442Y96969D03*
X1221986Y54843D03*
X1230844D03*
X1219033Y52087D03*
X1227891D03*
X1236750D03*
X1224939Y49331D03*
X1233797D03*
X1221986Y69803D03*
X1230844D03*
X1219033Y67048D03*
X1227891D03*
X1236750D03*
X1224939Y64292D03*
X1233797D03*
X1213128Y54843D03*
X1216080Y49331D03*
Y64292D03*
X1213128Y69803D03*
X1224939Y79252D03*
X1233797D03*
X1227891Y82008D03*
X1236750D03*
X1230844Y84764D03*
X1221986D03*
X1219033Y82008D03*
X1221986Y99725D03*
X1230844D03*
X1219033Y96969D03*
X1227891D03*
X1224939Y94213D03*
X1233797D03*
X1236750Y96969D03*
X1216080Y79252D03*
Y94213D03*
X1213128Y84764D03*
Y99725D03*
X1265293Y54843D03*
X1274151D03*
X1262340Y52087D03*
X1271198D03*
X1280057D03*
X1268246Y49331D03*
X1277104D03*
X1265293Y69803D03*
X1274151D03*
X1262340Y67048D03*
X1271198D03*
X1280057D03*
X1268246Y64292D03*
X1277104D03*
X1256435Y54843D03*
X1259387Y49331D03*
Y64292D03*
X1256435Y69803D03*
X1268246Y79252D03*
X1277104D03*
X1271198Y82008D03*
X1280057D03*
X1274151Y84764D03*
X1265293D03*
X1262340Y82008D03*
X1265293Y99725D03*
X1274151D03*
X1262340Y96969D03*
X1271198D03*
X1268246Y94213D03*
X1277104D03*
X1280057Y96969D03*
X1259387Y79252D03*
Y94213D03*
X1256435Y84764D03*
Y99725D03*
G54D65*
X1027722Y-9125D03*
X1054494D03*
G54D29*
X92990Y252362D03*
X116790D03*
X1301120Y173278D03*
Y183908D03*
G54D39*
X120351Y626636D03*
X126851D03*
X143217Y498160D03*
X156862Y498211D03*
X152916Y497936D03*
X146960Y498030D03*
X165851Y624136D03*
X137551Y622136D03*
X149851Y624136D03*
X155851D03*
X160851D03*
X217000Y534700D03*
X221000Y525700D03*
X500332Y130164D03*
X493245Y130025D03*
X489680Y130005D03*
X503827Y130104D03*
X563002Y133795D03*
X559591D03*
X597044Y130268D03*
X593636D03*
X600522Y130253D03*
X603924D03*
X635500Y346300D03*
X630500D03*
X627000D03*
X639000D03*
X848660Y785690D03*
X1175156Y134519D03*
X1171622Y136228D03*
X1168207Y136226D03*
X1178558Y134518D03*
X1240709Y146753D03*
X1237308D03*
X1269834Y143834D03*
X1266432D03*
X1289500Y274200D03*
G54D66*
X1025679Y31110D03*
Y28550D03*
Y25990D03*
Y23435D03*
X1015079D03*
Y25990D03*
Y28550D03*
Y31110D03*
G54D48*
X285900Y148900D03*
X307300Y780100D03*
X579234Y243270D03*
X626863Y233108D03*
X700800Y817300D03*
X721887Y201942D03*
X1168407Y823010D03*
X1312300Y271400D03*
X1329500Y817400D03*
G54D57*
X526215Y184000D03*
X565585D03*
G54D67*
X1039500Y50700D03*
G54D58*
X856650Y16200D03*
X864150Y20075D03*
Y12325D03*
G54D49*
X282300Y143300D03*
X632363Y238108D03*
X652600Y788200D03*
X952200Y44100D03*
X1318700Y266500D03*
X1369100Y254500D03*
G54D59*
X883500Y36100D03*
X879500Y44900D03*
X887500D03*
G54D68*
X1039500Y56300D03*
G54D69*
X1030000Y50150D03*
X1026125Y57650D03*
X1033875D03*
M02*
